FILE_TYPE = MACRO_DRAWING;
SET COLOR_WIRE YELLOW;
SET COLOR_PROP ORANGE;
SET COLOR_DOT WHITE;
SET COLOR_ARC YELLOW;
SET COLOR_BODY GREEN;
SET COLOR_NOTE PURPLE;
SET PROP_DISPLAY VALUE;
SET PAGE_NUMBER P51;
FORCEADD TAP..1
R 2
(-1100 50);
FORCEPROP 3 LASTPIN (-1050 50) SIG_NAME M_A_CPU1_CLK_DN<0>
J 0
(-1040 60);
DISPLAY 0.659574 (-1040 60);
PAINT MONO (-1040 60);
DISPLAY INVISIBLE (-1040 60);
FORCEPROP 1 LASTPIN (-1050 50) BN 0
J 2
(-1038 58);
DISPLAY 0.680851 (-1038 58);
PAINT GREEN (-1038 58);
FORCEPROP 2 LAST CDS_LIB standard
J 0
(-1100 50);
DISPLAY INVISIBLE (-1100 50);
FORCEPROP 1 LAST BODY_TYPE PLUMBING
J 2
(-1100 100);
DISPLAY 0.872340 (-1100 100);
PAINT GREEN (-1100 100);
DISPLAY INVISIBLE (-1100 100);
FORCEPROP 1 LAST HDL_TAP TRUE
J 2
(-1425 -75);
DISPLAY 0.872340 (-1425 -75);
DISPLAY INVISIBLE (-1425 -75);
FORCEPROP 1 LAST PATH I1
J 2
(-1098 50);
DISPLAY 0.872340 (-1098 50);
PAINT GREEN (-1098 50);
DISPLAY INVISIBLE (-1098 50);
FORCEADD TAP..1
R 2
(-1100 350);
FORCEPROP 3 LASTPIN (-1050 350) SIG_NAME M_A_CPU1_SB_CB<1>
J 0
(-1040 360);
DISPLAY 0.659574 (-1040 360);
PAINT MONO (-1040 360);
DISPLAY INVISIBLE (-1040 360);
FORCEPROP 1 LASTPIN (-1050 350) BN 1
J 2
(-1038 358);
DISPLAY 0.680851 (-1038 358);
PAINT GREEN (-1038 358);
FORCEPROP 2 LAST CDS_LIB standard
J 0
(-1100 350);
DISPLAY INVISIBLE (-1100 350);
FORCEPROP 1 LAST BODY_TYPE PLUMBING
J 2
(-1100 400);
DISPLAY 0.872340 (-1100 400);
PAINT GREEN (-1100 400);
DISPLAY INVISIBLE (-1100 400);
FORCEPROP 1 LAST HDL_TAP TRUE
J 2
(-1425 225);
DISPLAY 0.872340 (-1425 225);
DISPLAY INVISIBLE (-1425 225);
FORCEPROP 1 LAST PATH I10
J 2
(-1098 350);
DISPLAY 0.872340 (-1098 350);
PAINT GREEN (-1098 350);
DISPLAY INVISIBLE (-1098 350);
FORCEADD TAP..1
(2325 950);
FORCEPROP 3 LASTPIN (2275 950) SIG_NAME M_A_CPU1_SA_CS_N<3>
J 0
(2285 960);
DISPLAY 0.659574 (2285 960);
PAINT MONO (2285 960);
DISPLAY INVISIBLE (2285 960);
FORCEPROP 1 LASTPIN (2275 950) BN 3
J 0
(2263 958);
DISPLAY 0.680851 (2263 958);
PAINT GREEN (2263 958);
FORCEPROP 2 LAST CDS_LIB standard
J 0
(2325 950);
DISPLAY INVISIBLE (2325 950);
FORCEPROP 1 LAST BODY_TYPE PLUMBING
J 0
(2325 1000);
DISPLAY 0.872340 (2325 1000);
PAINT GREEN (2325 1000);
DISPLAY INVISIBLE (2325 1000);
FORCEPROP 1 LAST HDL_TAP TRUE
J 0
(2650 825);
DISPLAY 0.872340 (2650 825);
DISPLAY INVISIBLE (2650 825);
FORCEPROP 1 LAST PATH I100
J 0
(2323 950);
DISPLAY 0.872340 (2323 950);
PAINT GREEN (2323 950);
DISPLAY INVISIBLE (2323 950);
FORCEADD TAP..1
(2325 1150);
FORCEPROP 3 LASTPIN (2275 1150) SIG_NAME M_A_CPU1_SB_CA<0>
J 0
(2285 1160);
DISPLAY 0.659574 (2285 1160);
PAINT MONO (2285 1160);
DISPLAY INVISIBLE (2285 1160);
FORCEPROP 1 LASTPIN (2275 1150) BN 0
J 0
(2263 1158);
DISPLAY 0.680851 (2263 1158);
PAINT GREEN (2263 1158);
FORCEPROP 2 LAST CDS_LIB standard
J 0
(2325 1150);
DISPLAY INVISIBLE (2325 1150);
FORCEPROP 1 LAST BODY_TYPE PLUMBING
J 0
(2325 1200);
DISPLAY 0.872340 (2325 1200);
PAINT GREEN (2325 1200);
DISPLAY INVISIBLE (2325 1200);
FORCEPROP 1 LAST HDL_TAP TRUE
J 0
(2650 1025);
DISPLAY 0.872340 (2650 1025);
DISPLAY INVISIBLE (2650 1025);
FORCEPROP 1 LAST PATH I101
J 0
(2323 1150);
DISPLAY 0.872340 (2323 1150);
PAINT GREEN (2323 1150);
DISPLAY INVISIBLE (2323 1150);
FORCEADD TAP..1
(2325 1200);
FORCEPROP 3 LASTPIN (2275 1200) SIG_NAME M_A_CPU1_SB_CA<1>
J 0
(2285 1210);
DISPLAY 0.659574 (2285 1210);
PAINT MONO (2285 1210);
DISPLAY INVISIBLE (2285 1210);
FORCEPROP 1 LASTPIN (2275 1200) BN 1
J 0
(2263 1208);
DISPLAY 0.680851 (2263 1208);
PAINT GREEN (2263 1208);
FORCEPROP 2 LAST CDS_LIB standard
J 0
(2325 1200);
DISPLAY INVISIBLE (2325 1200);
FORCEPROP 1 LAST BODY_TYPE PLUMBING
J 0
(2325 1250);
DISPLAY 0.872340 (2325 1250);
PAINT GREEN (2325 1250);
DISPLAY INVISIBLE (2325 1250);
FORCEPROP 1 LAST HDL_TAP TRUE
J 0
(2650 1075);
DISPLAY 0.872340 (2650 1075);
DISPLAY INVISIBLE (2650 1075);
FORCEPROP 1 LAST PATH I102
J 0
(2323 1200);
DISPLAY 0.872340 (2323 1200);
PAINT GREEN (2323 1200);
DISPLAY INVISIBLE (2323 1200);
FORCEADD TAP..1
(2325 1300);
FORCEPROP 3 LASTPIN (2275 1300) SIG_NAME M_A_CPU1_SB_CA<3>
J 0
(2285 1310);
DISPLAY 0.659574 (2285 1310);
PAINT MONO (2285 1310);
DISPLAY INVISIBLE (2285 1310);
FORCEPROP 1 LASTPIN (2275 1300) BN 3
J 0
(2263 1308);
DISPLAY 0.680851 (2263 1308);
PAINT GREEN (2263 1308);
FORCEPROP 2 LAST CDS_LIB standard
J 0
(2325 1300);
DISPLAY INVISIBLE (2325 1300);
FORCEPROP 1 LAST BODY_TYPE PLUMBING
J 0
(2325 1350);
DISPLAY 0.872340 (2325 1350);
PAINT GREEN (2325 1350);
DISPLAY INVISIBLE (2325 1350);
FORCEPROP 1 LAST HDL_TAP TRUE
J 0
(2650 1175);
DISPLAY 0.872340 (2650 1175);
DISPLAY INVISIBLE (2650 1175);
FORCEPROP 1 LAST PATH I103
J 0
(2323 1300);
DISPLAY 0.872340 (2323 1300);
PAINT GREEN (2323 1300);
DISPLAY INVISIBLE (2323 1300);
FORCEADD TAP..1
(2325 1250);
FORCEPROP 3 LASTPIN (2275 1250) SIG_NAME M_A_CPU1_SB_CA<2>
J 0
(2285 1260);
DISPLAY 0.659574 (2285 1260);
PAINT MONO (2285 1260);
DISPLAY INVISIBLE (2285 1260);
FORCEPROP 1 LASTPIN (2275 1250) BN 2
J 0
(2263 1258);
DISPLAY 0.680851 (2263 1258);
PAINT GREEN (2263 1258);
FORCEPROP 2 LAST CDS_LIB standard
J 0
(2325 1250);
DISPLAY INVISIBLE (2325 1250);
FORCEPROP 1 LAST BODY_TYPE PLUMBING
J 0
(2325 1300);
DISPLAY 0.872340 (2325 1300);
PAINT GREEN (2325 1300);
DISPLAY INVISIBLE (2325 1300);
FORCEPROP 1 LAST HDL_TAP TRUE
J 0
(2650 1125);
DISPLAY 0.872340 (2650 1125);
DISPLAY INVISIBLE (2650 1125);
FORCEPROP 1 LAST PATH I104
J 0
(2323 1250);
DISPLAY 0.872340 (2323 1250);
PAINT GREEN (2323 1250);
DISPLAY INVISIBLE (2323 1250);
FORCEADD TAP..1
(2325 1400);
FORCEPROP 3 LASTPIN (2275 1400) SIG_NAME M_A_CPU1_SB_CA<5>
J 0
(2285 1410);
DISPLAY 0.659574 (2285 1410);
PAINT MONO (2285 1410);
DISPLAY INVISIBLE (2285 1410);
FORCEPROP 1 LASTPIN (2275 1400) BN 5
J 0
(2263 1408);
DISPLAY 0.680851 (2263 1408);
PAINT GREEN (2263 1408);
FORCEPROP 2 LAST CDS_LIB standard
J 0
(2325 1400);
DISPLAY INVISIBLE (2325 1400);
FORCEPROP 1 LAST BODY_TYPE PLUMBING
J 0
(2325 1450);
DISPLAY 0.872340 (2325 1450);
PAINT GREEN (2325 1450);
DISPLAY INVISIBLE (2325 1450);
FORCEPROP 1 LAST HDL_TAP TRUE
J 0
(2650 1275);
DISPLAY 0.872340 (2650 1275);
DISPLAY INVISIBLE (2650 1275);
FORCEPROP 1 LAST PATH I105
J 0
(2323 1400);
DISPLAY 0.872340 (2323 1400);
PAINT GREEN (2323 1400);
DISPLAY INVISIBLE (2323 1400);
FORCEADD TAP..1
(2325 1450);
FORCEPROP 3 LASTPIN (2275 1450) SIG_NAME M_A_CPU1_SB_CA<6>
J 0
(2285 1460);
DISPLAY 0.659574 (2285 1460);
PAINT MONO (2285 1460);
DISPLAY INVISIBLE (2285 1460);
FORCEPROP 1 LASTPIN (2275 1450) BN 6
J 0
(2263 1458);
DISPLAY 0.680851 (2263 1458);
PAINT GREEN (2263 1458);
FORCEPROP 2 LAST CDS_LIB standard
J 0
(2325 1450);
DISPLAY INVISIBLE (2325 1450);
FORCEPROP 1 LAST BODY_TYPE PLUMBING
J 0
(2325 1500);
DISPLAY 0.872340 (2325 1500);
PAINT GREEN (2325 1500);
DISPLAY INVISIBLE (2325 1500);
FORCEPROP 1 LAST HDL_TAP TRUE
J 0
(2650 1325);
DISPLAY 0.872340 (2650 1325);
DISPLAY INVISIBLE (2650 1325);
FORCEPROP 1 LAST PATH I106
J 0
(2323 1450);
DISPLAY 0.872340 (2323 1450);
PAINT GREEN (2323 1450);
DISPLAY INVISIBLE (2323 1450);
FORCEADD TAP..1
(2325 1350);
FORCEPROP 3 LASTPIN (2275 1350) SIG_NAME M_A_CPU1_SB_CA<4>
J 0
(2285 1360);
DISPLAY 0.659574 (2285 1360);
PAINT MONO (2285 1360);
DISPLAY INVISIBLE (2285 1360);
FORCEPROP 1 LASTPIN (2275 1350) BN 4
J 0
(2263 1358);
DISPLAY 0.680851 (2263 1358);
PAINT GREEN (2263 1358);
FORCEPROP 2 LAST CDS_LIB standard
J 0
(2325 1350);
DISPLAY INVISIBLE (2325 1350);
FORCEPROP 1 LAST BODY_TYPE PLUMBING
J 0
(2325 1400);
DISPLAY 0.872340 (2325 1400);
PAINT GREEN (2325 1400);
DISPLAY INVISIBLE (2325 1400);
FORCEPROP 1 LAST HDL_TAP TRUE
J 0
(2650 1225);
DISPLAY 0.872340 (2650 1225);
DISPLAY INVISIBLE (2650 1225);
FORCEPROP 1 LAST PATH I107
J 0
(2323 1350);
DISPLAY 0.872340 (2323 1350);
PAINT GREEN (2323 1350);
DISPLAY INVISIBLE (2323 1350);
FORCEADD TAP..1
(2325 1650);
FORCEPROP 3 LASTPIN (2275 1650) SIG_NAME M_A_CPU1_SA_CA<0>
J 0
(2285 1660);
DISPLAY 0.659574 (2285 1660);
PAINT MONO (2285 1660);
DISPLAY INVISIBLE (2285 1660);
FORCEPROP 1 LASTPIN (2275 1650) BN 0
J 0
(2263 1658);
DISPLAY 0.680851 (2263 1658);
PAINT GREEN (2263 1658);
FORCEPROP 2 LAST CDS_LIB standard
J 0
(2325 1650);
DISPLAY INVISIBLE (2325 1650);
FORCEPROP 1 LAST BODY_TYPE PLUMBING
J 0
(2325 1700);
DISPLAY 0.872340 (2325 1700);
PAINT GREEN (2325 1700);
DISPLAY INVISIBLE (2325 1700);
FORCEPROP 1 LAST HDL_TAP TRUE
J 0
(2650 1525);
DISPLAY 0.872340 (2650 1525);
DISPLAY INVISIBLE (2650 1525);
FORCEPROP 1 LAST PATH I108
J 0
(2323 1650);
DISPLAY 0.872340 (2323 1650);
PAINT GREEN (2323 1650);
DISPLAY INVISIBLE (2323 1650);
FORCEADD TAP..1
(2325 1700);
FORCEPROP 3 LASTPIN (2275 1700) SIG_NAME M_A_CPU1_SA_CA<1>
J 0
(2285 1710);
DISPLAY 0.659574 (2285 1710);
PAINT MONO (2285 1710);
DISPLAY INVISIBLE (2285 1710);
FORCEPROP 1 LASTPIN (2275 1700) BN 1
J 0
(2263 1708);
DISPLAY 0.680851 (2263 1708);
PAINT GREEN (2263 1708);
FORCEPROP 2 LAST CDS_LIB standard
J 0
(2325 1700);
DISPLAY INVISIBLE (2325 1700);
FORCEPROP 1 LAST BODY_TYPE PLUMBING
J 0
(2325 1750);
DISPLAY 0.872340 (2325 1750);
PAINT GREEN (2325 1750);
DISPLAY INVISIBLE (2325 1750);
FORCEPROP 1 LAST HDL_TAP TRUE
J 0
(2650 1575);
DISPLAY 0.872340 (2650 1575);
DISPLAY INVISIBLE (2650 1575);
FORCEPROP 1 LAST PATH I109
J 0
(2323 1700);
DISPLAY 0.872340 (2323 1700);
PAINT GREEN (2323 1700);
DISPLAY INVISIBLE (2323 1700);
FORCEADD TAP..1
R 2
(-1100 400);
FORCEPROP 3 LASTPIN (-1050 400) SIG_NAME M_A_CPU1_SB_CB<2>
J 0
(-1040 410);
DISPLAY 0.659574 (-1040 410);
PAINT MONO (-1040 410);
DISPLAY INVISIBLE (-1040 410);
FORCEPROP 1 LASTPIN (-1050 400) BN 2
J 2
(-1038 408);
DISPLAY 0.680851 (-1038 408);
PAINT GREEN (-1038 408);
FORCEPROP 2 LAST CDS_LIB standard
J 0
(-1100 400);
DISPLAY INVISIBLE (-1100 400);
FORCEPROP 1 LAST BODY_TYPE PLUMBING
J 2
(-1100 450);
DISPLAY 0.872340 (-1100 450);
PAINT GREEN (-1100 450);
DISPLAY INVISIBLE (-1100 450);
FORCEPROP 1 LAST HDL_TAP TRUE
J 2
(-1425 275);
DISPLAY 0.872340 (-1425 275);
DISPLAY INVISIBLE (-1425 275);
FORCEPROP 1 LAST PATH I11
J 2
(-1098 400);
DISPLAY 0.872340 (-1098 400);
PAINT GREEN (-1098 400);
DISPLAY INVISIBLE (-1098 400);
FORCEADD TAP..1
(2325 1750);
FORCEPROP 3 LASTPIN (2275 1750) SIG_NAME M_A_CPU1_SA_CA<2>
J 0
(2285 1760);
DISPLAY 0.659574 (2285 1760);
PAINT MONO (2285 1760);
DISPLAY INVISIBLE (2285 1760);
FORCEPROP 1 LASTPIN (2275 1750) BN 2
J 0
(2263 1758);
DISPLAY 0.680851 (2263 1758);
PAINT GREEN (2263 1758);
FORCEPROP 2 LAST CDS_LIB standard
J 0
(2325 1750);
DISPLAY INVISIBLE (2325 1750);
FORCEPROP 1 LAST BODY_TYPE PLUMBING
J 0
(2325 1800);
DISPLAY 0.872340 (2325 1800);
PAINT GREEN (2325 1800);
DISPLAY INVISIBLE (2325 1800);
FORCEPROP 1 LAST HDL_TAP TRUE
J 0
(2650 1625);
DISPLAY 0.872340 (2650 1625);
DISPLAY INVISIBLE (2650 1625);
FORCEPROP 1 LAST PATH I110
J 0
(2323 1750);
DISPLAY 0.872340 (2323 1750);
PAINT GREEN (2323 1750);
DISPLAY INVISIBLE (2323 1750);
FORCEADD TAP..1
(2325 1800);
FORCEPROP 3 LASTPIN (2275 1800) SIG_NAME M_A_CPU1_SA_CA<3>
J 0
(2285 1810);
DISPLAY 0.659574 (2285 1810);
PAINT MONO (2285 1810);
DISPLAY INVISIBLE (2285 1810);
FORCEPROP 1 LASTPIN (2275 1800) BN 3
J 0
(2263 1808);
DISPLAY 0.680851 (2263 1808);
PAINT GREEN (2263 1808);
FORCEPROP 2 LAST CDS_LIB standard
J 0
(2325 1800);
DISPLAY INVISIBLE (2325 1800);
FORCEPROP 1 LAST BODY_TYPE PLUMBING
J 0
(2325 1850);
DISPLAY 0.872340 (2325 1850);
PAINT GREEN (2325 1850);
DISPLAY INVISIBLE (2325 1850);
FORCEPROP 1 LAST HDL_TAP TRUE
J 0
(2650 1675);
DISPLAY 0.872340 (2650 1675);
DISPLAY INVISIBLE (2650 1675);
FORCEPROP 1 LAST PATH I111
J 0
(2323 1800);
DISPLAY 0.872340 (2323 1800);
PAINT GREEN (2323 1800);
DISPLAY INVISIBLE (2323 1800);
FORCEADD TAP..1
(2325 1950);
FORCEPROP 3 LASTPIN (2275 1950) SIG_NAME M_A_CPU1_SA_CA<6>
J 0
(2285 1960);
DISPLAY 0.659574 (2285 1960);
PAINT MONO (2285 1960);
DISPLAY INVISIBLE (2285 1960);
FORCEPROP 1 LASTPIN (2275 1950) BN 6
J 0
(2263 1958);
DISPLAY 0.680851 (2263 1958);
PAINT GREEN (2263 1958);
FORCEPROP 2 LAST CDS_LIB standard
J 0
(2325 1950);
DISPLAY INVISIBLE (2325 1950);
FORCEPROP 1 LAST BODY_TYPE PLUMBING
J 0
(2325 2000);
DISPLAY 0.872340 (2325 2000);
PAINT GREEN (2325 2000);
DISPLAY INVISIBLE (2325 2000);
FORCEPROP 1 LAST HDL_TAP TRUE
J 0
(2650 1825);
DISPLAY 0.872340 (2650 1825);
DISPLAY INVISIBLE (2650 1825);
FORCEPROP 1 LAST PATH I112
J 0
(2323 1950);
DISPLAY 0.872340 (2323 1950);
PAINT GREEN (2323 1950);
DISPLAY INVISIBLE (2323 1950);
FORCEADD TAP..1
(2325 1850);
FORCEPROP 3 LASTPIN (2275 1850) SIG_NAME M_A_CPU1_SA_CA<4>
J 0
(2285 1860);
DISPLAY 0.659574 (2285 1860);
PAINT MONO (2285 1860);
DISPLAY INVISIBLE (2285 1860);
FORCEPROP 1 LASTPIN (2275 1850) BN 4
J 0
(2263 1858);
DISPLAY 0.680851 (2263 1858);
PAINT GREEN (2263 1858);
FORCEPROP 2 LAST CDS_LIB standard
J 0
(2325 1850);
DISPLAY INVISIBLE (2325 1850);
FORCEPROP 1 LAST BODY_TYPE PLUMBING
J 0
(2325 1900);
DISPLAY 0.872340 (2325 1900);
PAINT GREEN (2325 1900);
DISPLAY INVISIBLE (2325 1900);
FORCEPROP 1 LAST HDL_TAP TRUE
J 0
(2650 1725);
DISPLAY 0.872340 (2650 1725);
DISPLAY INVISIBLE (2650 1725);
FORCEPROP 1 LAST PATH I113
J 0
(2323 1850);
DISPLAY 0.872340 (2323 1850);
PAINT GREEN (2323 1850);
DISPLAY INVISIBLE (2323 1850);
FORCEADD TAP..1
(2325 1900);
FORCEPROP 3 LASTPIN (2275 1900) SIG_NAME M_A_CPU1_SA_CA<5>
J 0
(2285 1910);
DISPLAY 0.659574 (2285 1910);
PAINT MONO (2285 1910);
DISPLAY INVISIBLE (2285 1910);
FORCEPROP 1 LASTPIN (2275 1900) BN 5
J 0
(2263 1908);
DISPLAY 0.680851 (2263 1908);
PAINT GREEN (2263 1908);
FORCEPROP 2 LAST CDS_LIB standard
J 0
(2325 1900);
DISPLAY INVISIBLE (2325 1900);
FORCEPROP 1 LAST BODY_TYPE PLUMBING
J 0
(2325 1950);
DISPLAY 0.872340 (2325 1950);
PAINT GREEN (2325 1950);
DISPLAY INVISIBLE (2325 1950);
FORCEPROP 1 LAST HDL_TAP TRUE
J 0
(2650 1775);
DISPLAY 0.872340 (2650 1775);
DISPLAY INVISIBLE (2650 1775);
FORCEPROP 1 LAST PATH I114
J 0
(2323 1900);
DISPLAY 0.872340 (2323 1900);
PAINT GREEN (2323 1900);
DISPLAY INVISIBLE (2323 1900);
FORCEADD OFFPAGE..4
(3425 150);
FORCEPROP 2 LAST $XR0 98 
J 0
(3611 150);
DISPLAY 0.638298 (3611 150);
PAINT MONO (3611 150);
FORCEPROP 2 LAST CDS_LIB standard
J 0
(3425 150);
PAINT MONO (3425 150);
DISPLAY INVISIBLE (3425 150);
FORCEPROP 1 LAST OFFPAGE TRUE
J 0
(3750 25);
DISPLAY 1.170213 (3750 25);
PAINT GREEN (3750 25);
DISPLAY INVISIBLE (3750 25);
FORCEPROP 1 LAST COMMENT_BODY TRUE
J 0
(3400 50);
DISPLAY 1.170213 (3400 50);
PAINT GREEN (3400 50);
DISPLAY INVISIBLE (3400 50);
FORCEPROP 2 LAST PATH I115
J 0
(3600 225);
DISPLAY 1.021277 (3600 225);
DISPLAY INVISIBLE (3600 225);
FORCEADD OFFPAGE..4
(3425 200);
FORCEPROP 2 LAST $XR0 99 
J 0
(3611 200);
DISPLAY 0.638298 (3611 200);
PAINT MONO (3611 200);
FORCEPROP 2 LAST CDS_LIB standard
J 0
(3425 200);
PAINT MONO (3425 200);
DISPLAY INVISIBLE (3425 200);
FORCEPROP 1 LAST OFFPAGE TRUE
J 0
(3750 75);
DISPLAY 1.170213 (3750 75);
PAINT GREEN (3750 75);
DISPLAY INVISIBLE (3750 75);
FORCEPROP 1 LAST COMMENT_BODY TRUE
J 0
(3400 100);
DISPLAY 1.170213 (3400 100);
PAINT GREEN (3400 100);
DISPLAY INVISIBLE (3400 100);
FORCEPROP 2 LAST PATH I116
J 0
(3600 275);
DISPLAY 1.021277 (3600 275);
DISPLAY INVISIBLE (3600 275);
FORCEADD OFFPAGE..4
(3425 300);
FORCEPROP 2 LAST $XR0 98 
J 0
(3611 300);
DISPLAY 0.638298 (3611 300);
PAINT MONO (3611 300);
FORCEPROP 2 LAST CDS_LIB standard
J 0
(3425 300);
PAINT MONO (3425 300);
DISPLAY INVISIBLE (3425 300);
FORCEPROP 1 LAST OFFPAGE TRUE
J 0
(3750 175);
DISPLAY 1.170213 (3750 175);
PAINT GREEN (3750 175);
DISPLAY INVISIBLE (3750 175);
FORCEPROP 1 LAST COMMENT_BODY TRUE
J 0
(3400 200);
DISPLAY 1.170213 (3400 200);
PAINT GREEN (3400 200);
DISPLAY INVISIBLE (3400 200);
FORCEPROP 2 LAST PATH I117
J 0
(3600 375);
DISPLAY 1.021277 (3600 375);
DISPLAY INVISIBLE (3600 375);
FORCEADD OFFPAGE..4
(3425 350);
FORCEPROP 2 LAST $XR0 99 
J 0
(3611 350);
DISPLAY 0.638298 (3611 350);
PAINT MONO (3611 350);
FORCEPROP 2 LAST CDS_LIB standard
J 0
(3425 350);
PAINT MONO (3425 350);
DISPLAY INVISIBLE (3425 350);
FORCEPROP 1 LAST OFFPAGE TRUE
J 0
(3750 225);
DISPLAY 1.170213 (3750 225);
PAINT GREEN (3750 225);
DISPLAY INVISIBLE (3750 225);
FORCEPROP 1 LAST COMMENT_BODY TRUE
J 0
(3400 250);
DISPLAY 1.170213 (3400 250);
PAINT GREEN (3400 250);
DISPLAY INVISIBLE (3400 250);
FORCEPROP 2 LAST PATH I118
J 0
(3600 425);
DISPLAY 1.021277 (3600 425);
DISPLAY INVISIBLE (3600 425);
FORCEADD OFFPAGE..2
(3425 675);
FORCEPROP 2 LAST $XR1 99 
J 0
(3704 675);
DISPLAY 0.638298 (3704 675);
PAINT MONO (3704 675);
FORCEPROP 2 LAST $XR0 98 
J 0
(3614 675);
DISPLAY 0.638298 (3614 675);
PAINT MONO (3614 675);
FORCEPROP 2 LAST CDS_LIB standard
J 0
(3425 675);
PAINT MONO (3425 675);
DISPLAY INVISIBLE (3425 675);
FORCEPROP 1 LAST OFFPAGE TRUE
J 0
(3750 550);
DISPLAY 1.170213 (3750 550);
PAINT GREEN (3750 550);
DISPLAY INVISIBLE (3750 550);
FORCEPROP 1 LAST COMMENT_BODY TRUE
J 0
(3380 580);
DISPLAY 1.170213 (3380 580);
PAINT GREEN (3380 580);
DISPLAY INVISIBLE (3380 580);
FORCEPROP 2 LAST PATH I119
J 0
(3600 750);
DISPLAY 1.021277 (3600 750);
DISPLAY INVISIBLE (3600 750);
FORCEADD TAP..1
R 2
(-1100 500);
FORCEPROP 3 LASTPIN (-1050 500) SIG_NAME M_A_CPU1_SB_CB<4>
J 0
(-1040 510);
DISPLAY 0.659574 (-1040 510);
PAINT MONO (-1040 510);
DISPLAY INVISIBLE (-1040 510);
FORCEPROP 1 LASTPIN (-1050 500) BN 4
J 2
(-1038 508);
DISPLAY 0.680851 (-1038 508);
PAINT GREEN (-1038 508);
FORCEPROP 2 LAST CDS_LIB standard
J 0
(-1100 500);
DISPLAY INVISIBLE (-1100 500);
FORCEPROP 1 LAST BODY_TYPE PLUMBING
J 2
(-1100 550);
DISPLAY 0.872340 (-1100 550);
PAINT GREEN (-1100 550);
DISPLAY INVISIBLE (-1100 550);
FORCEPROP 1 LAST HDL_TAP TRUE
J 2
(-1425 375);
DISPLAY 0.872340 (-1425 375);
DISPLAY INVISIBLE (-1425 375);
FORCEPROP 1 LAST PATH I12
J 2
(-1098 500);
DISPLAY 0.872340 (-1098 500);
PAINT GREEN (-1098 500);
DISPLAY INVISIBLE (-1098 500);
FORCEADD OFFPAGE..2
(3425 975);
FORCEPROP 2 LAST $XR1 99 
J 0
(3704 975);
DISPLAY 0.638298 (3704 975);
PAINT MONO (3704 975);
FORCEPROP 2 LAST $XR0 98 
J 0
(3614 975);
DISPLAY 0.638298 (3614 975);
PAINT MONO (3614 975);
FORCEPROP 2 LAST CDS_LIB standard
J 0
(3425 975);
PAINT MONO (3425 975);
DISPLAY INVISIBLE (3425 975);
FORCEPROP 1 LAST OFFPAGE TRUE
J 0
(3750 850);
DISPLAY 1.170213 (3750 850);
PAINT GREEN (3750 850);
DISPLAY INVISIBLE (3750 850);
FORCEPROP 1 LAST COMMENT_BODY TRUE
J 0
(3380 880);
DISPLAY 1.170213 (3380 880);
PAINT GREEN (3380 880);
DISPLAY INVISIBLE (3380 880);
FORCEPROP 2 LAST PATH I120
J 0
(3600 1050);
DISPLAY 1.021277 (3600 1050);
DISPLAY INVISIBLE (3600 1050);
FORCEADD OFFPAGE..2
(3425 1100);
FORCEPROP 2 LAST $XR1 99 
J 0
(3704 1100);
DISPLAY 0.638298 (3704 1100);
PAINT MONO (3704 1100);
FORCEPROP 2 LAST $XR0 98 
J 0
(3614 1100);
DISPLAY 0.638298 (3614 1100);
PAINT MONO (3614 1100);
FORCEPROP 2 LAST CDS_LIB standard
J 0
(3425 1100);
PAINT MONO (3425 1100);
DISPLAY INVISIBLE (3425 1100);
FORCEPROP 1 LAST OFFPAGE TRUE
J 0
(3750 975);
DISPLAY 1.170213 (3750 975);
PAINT GREEN (3750 975);
DISPLAY INVISIBLE (3750 975);
FORCEPROP 1 LAST COMMENT_BODY TRUE
J 0
(3380 1005);
DISPLAY 1.170213 (3380 1005);
PAINT GREEN (3380 1005);
DISPLAY INVISIBLE (3380 1005);
FORCEPROP 2 LAST PATH I121
J 0
(3600 1175);
DISPLAY 1.021277 (3600 1175);
DISPLAY INVISIBLE (3600 1175);
FORCEADD OFFPAGE..3
(3425 1475);
FORCEPROP 2 LAST $XR1 99 
J 0
(3729 1475);
DISPLAY 0.638298 (3729 1475);
PAINT MONO (3729 1475);
FORCEPROP 2 LAST $XR0 98 
J 0
(3639 1475);
DISPLAY 0.638298 (3639 1475);
PAINT MONO (3639 1475);
FORCEPROP 2 LAST CDS_LIB standard
J 2
(3425 1475);
DISPLAY INVISIBLE (3425 1475);
FORCEPROP 1 LAST OFFPAGE TRUE
J 0
(3750 1350);
DISPLAY 0.872340 (3750 1350);
DISPLAY INVISIBLE (3750 1350);
FORCEPROP 1 LAST COMMENT_BODY TRUE
J 0
(3375 1375);
DISPLAY 0.872340 (3375 1375);
PAINT GREEN (3375 1375);
DISPLAY INVISIBLE (3375 1375);
FORCEPROP 2 LAST PATH I122
J 0
(3625 1550);
DISPLAY 1.021277 (3625 1550);
DISPLAY INVISIBLE (3625 1550);
FORCEADD OFFPAGE..2
(3425 1600);
FORCEPROP 2 LAST $XR1 99 
J 0
(3704 1600);
DISPLAY 0.638298 (3704 1600);
PAINT MONO (3704 1600);
FORCEPROP 2 LAST $XR0 98 
J 0
(3614 1600);
DISPLAY 0.638298 (3614 1600);
PAINT MONO (3614 1600);
FORCEPROP 2 LAST CDS_LIB standard
J 0
(3425 1600);
PAINT MONO (3425 1600);
DISPLAY INVISIBLE (3425 1600);
FORCEPROP 1 LAST OFFPAGE TRUE
J 0
(3750 1475);
DISPLAY 1.170213 (3750 1475);
PAINT GREEN (3750 1475);
DISPLAY INVISIBLE (3750 1475);
FORCEPROP 1 LAST COMMENT_BODY TRUE
J 0
(3380 1505);
DISPLAY 1.170213 (3380 1505);
PAINT GREEN (3380 1505);
DISPLAY INVISIBLE (3380 1505);
FORCEPROP 2 LAST PATH I123
J 0
(3600 1675);
DISPLAY 1.021277 (3600 1675);
DISPLAY INVISIBLE (3600 1675);
FORCEADD OFFPAGE..3
(3425 1975);
FORCEPROP 2 LAST $XR1 99 
J 0
(3729 1975);
DISPLAY 0.638298 (3729 1975);
PAINT MONO (3729 1975);
FORCEPROP 2 LAST $XR0 98 
J 0
(3639 1975);
DISPLAY 0.638298 (3639 1975);
PAINT MONO (3639 1975);
FORCEPROP 2 LAST CDS_LIB standard
J 2
(3425 1975);
DISPLAY INVISIBLE (3425 1975);
FORCEPROP 1 LAST OFFPAGE TRUE
J 0
(3750 1850);
DISPLAY 0.872340 (3750 1850);
DISPLAY INVISIBLE (3750 1850);
FORCEPROP 1 LAST COMMENT_BODY TRUE
J 0
(3375 1875);
DISPLAY 0.872340 (3375 1875);
PAINT GREEN (3375 1875);
DISPLAY INVISIBLE (3375 1875);
FORCEPROP 2 LAST PATH I124
J 0
(3625 2050);
DISPLAY 1.021277 (3625 2050);
DISPLAY INVISIBLE (3625 2050);
FORCEADD TAP..1
(2325 2100);
FORCEPROP 3 LASTPIN (2275 2100) SIG_NAME M_A_CPU1_SB_DQS_DN<0>
J 0
(2285 2110);
DISPLAY 0.659574 (2285 2110);
PAINT MONO (2285 2110);
DISPLAY INVISIBLE (2285 2110);
FORCEPROP 1 LASTPIN (2275 2100) BN 0
J 0
(2263 2108);
DISPLAY 0.680851 (2263 2108);
PAINT GREEN (2263 2108);
FORCEPROP 2 LAST CDS_LIB standard
J 0
(2325 2100);
DISPLAY INVISIBLE (2325 2100);
FORCEPROP 1 LAST BODY_TYPE PLUMBING
J 0
(2325 2150);
DISPLAY 0.872340 (2325 2150);
PAINT GREEN (2325 2150);
DISPLAY INVISIBLE (2325 2150);
FORCEPROP 1 LAST HDL_TAP TRUE
J 0
(2650 1975);
DISPLAY 0.872340 (2650 1975);
DISPLAY INVISIBLE (2650 1975);
FORCEPROP 1 LAST PATH I125
J 0
(2323 2100);
DISPLAY 0.872340 (2323 2100);
PAINT GREEN (2323 2100);
DISPLAY INVISIBLE (2323 2100);
FORCEADD TAP..1
(2325 2200);
FORCEPROP 3 LASTPIN (2275 2200) SIG_NAME M_A_CPU1_SB_DQS_DN<2>
J 0
(2285 2210);
DISPLAY 0.659574 (2285 2210);
PAINT MONO (2285 2210);
DISPLAY INVISIBLE (2285 2210);
FORCEPROP 1 LASTPIN (2275 2200) BN 2
J 0
(2263 2208);
DISPLAY 0.680851 (2263 2208);
PAINT GREEN (2263 2208);
FORCEPROP 2 LAST CDS_LIB standard
J 0
(2325 2200);
DISPLAY INVISIBLE (2325 2200);
FORCEPROP 1 LAST BODY_TYPE PLUMBING
J 0
(2325 2250);
DISPLAY 0.872340 (2325 2250);
PAINT GREEN (2325 2250);
DISPLAY INVISIBLE (2325 2250);
FORCEPROP 1 LAST HDL_TAP TRUE
J 0
(2650 2075);
DISPLAY 0.872340 (2650 2075);
DISPLAY INVISIBLE (2650 2075);
FORCEPROP 1 LAST PATH I126
J 0
(2323 2200);
DISPLAY 0.872340 (2323 2200);
PAINT GREEN (2323 2200);
DISPLAY INVISIBLE (2323 2200);
FORCEADD TAP..1
(2325 2150);
FORCEPROP 3 LASTPIN (2275 2150) SIG_NAME M_A_CPU1_SB_DQS_DN<1>
J 0
(2285 2160);
DISPLAY 0.659574 (2285 2160);
PAINT MONO (2285 2160);
DISPLAY INVISIBLE (2285 2160);
FORCEPROP 1 LASTPIN (2275 2150) BN 1
J 0
(2263 2158);
DISPLAY 0.680851 (2263 2158);
PAINT GREEN (2263 2158);
FORCEPROP 2 LAST CDS_LIB standard
J 0
(2325 2150);
DISPLAY INVISIBLE (2325 2150);
FORCEPROP 1 LAST BODY_TYPE PLUMBING
J 0
(2325 2200);
DISPLAY 0.872340 (2325 2200);
PAINT GREEN (2325 2200);
DISPLAY INVISIBLE (2325 2200);
FORCEPROP 1 LAST HDL_TAP TRUE
J 0
(2650 2025);
DISPLAY 0.872340 (2650 2025);
DISPLAY INVISIBLE (2650 2025);
FORCEPROP 1 LAST PATH I127
J 0
(2323 2150);
DISPLAY 0.872340 (2323 2150);
PAINT GREEN (2323 2150);
DISPLAY INVISIBLE (2323 2150);
FORCEADD TAP..1
(2325 2250);
FORCEPROP 3 LASTPIN (2275 2250) SIG_NAME M_A_CPU1_SB_DQS_DN<3>
J 0
(2285 2260);
DISPLAY 0.659574 (2285 2260);
PAINT MONO (2285 2260);
DISPLAY INVISIBLE (2285 2260);
FORCEPROP 1 LASTPIN (2275 2250) BN 3
J 0
(2263 2258);
DISPLAY 0.680851 (2263 2258);
PAINT GREEN (2263 2258);
FORCEPROP 2 LAST CDS_LIB standard
J 0
(2325 2250);
DISPLAY INVISIBLE (2325 2250);
FORCEPROP 1 LAST BODY_TYPE PLUMBING
J 0
(2325 2300);
DISPLAY 0.872340 (2325 2300);
PAINT GREEN (2325 2300);
DISPLAY INVISIBLE (2325 2300);
FORCEPROP 1 LAST HDL_TAP TRUE
J 0
(2650 2125);
DISPLAY 0.872340 (2650 2125);
DISPLAY INVISIBLE (2650 2125);
FORCEPROP 1 LAST PATH I128
J 0
(2323 2250);
DISPLAY 0.872340 (2323 2250);
PAINT GREEN (2323 2250);
DISPLAY INVISIBLE (2323 2250);
FORCEADD TAP..1
(2325 2300);
FORCEPROP 3 LASTPIN (2275 2300) SIG_NAME M_A_CPU1_SB_DQS_DN<4>
J 0
(2285 2310);
DISPLAY 0.659574 (2285 2310);
PAINT MONO (2285 2310);
DISPLAY INVISIBLE (2285 2310);
FORCEPROP 1 LASTPIN (2275 2300) BN 4
J 0
(2263 2308);
DISPLAY 0.680851 (2263 2308);
PAINT GREEN (2263 2308);
FORCEPROP 2 LAST CDS_LIB standard
J 0
(2325 2300);
DISPLAY INVISIBLE (2325 2300);
FORCEPROP 1 LAST BODY_TYPE PLUMBING
J 0
(2325 2350);
DISPLAY 0.872340 (2325 2350);
PAINT GREEN (2325 2350);
DISPLAY INVISIBLE (2325 2350);
FORCEPROP 1 LAST HDL_TAP TRUE
J 0
(2650 2175);
DISPLAY 0.872340 (2650 2175);
DISPLAY INVISIBLE (2650 2175);
FORCEPROP 1 LAST PATH I129
J 0
(2323 2300);
DISPLAY 0.872340 (2323 2300);
PAINT GREEN (2323 2300);
DISPLAY INVISIBLE (2323 2300);
FORCEADD TAP..1
R 2
(-1100 450);
FORCEPROP 3 LASTPIN (-1050 450) SIG_NAME M_A_CPU1_SB_CB<3>
J 0
(-1040 460);
DISPLAY 0.659574 (-1040 460);
PAINT MONO (-1040 460);
DISPLAY INVISIBLE (-1040 460);
FORCEPROP 1 LASTPIN (-1050 450) BN 3
J 2
(-1038 458);
DISPLAY 0.680851 (-1038 458);
PAINT GREEN (-1038 458);
FORCEPROP 2 LAST CDS_LIB standard
J 0
(-1100 450);
DISPLAY INVISIBLE (-1100 450);
FORCEPROP 1 LAST BODY_TYPE PLUMBING
J 2
(-1100 500);
DISPLAY 0.872340 (-1100 500);
PAINT GREEN (-1100 500);
DISPLAY INVISIBLE (-1100 500);
FORCEPROP 1 LAST HDL_TAP TRUE
J 2
(-1425 325);
DISPLAY 0.872340 (-1425 325);
DISPLAY INVISIBLE (-1425 325);
FORCEPROP 1 LAST PATH I13
J 2
(-1098 450);
DISPLAY 0.872340 (-1098 450);
PAINT GREEN (-1098 450);
DISPLAY INVISIBLE (-1098 450);
FORCEADD TAP..1
(2325 2350);
FORCEPROP 3 LASTPIN (2275 2350) SIG_NAME M_A_CPU1_SB_DQS_DN<5>
J 0
(2285 2360);
DISPLAY 0.659574 (2285 2360);
PAINT MONO (2285 2360);
DISPLAY INVISIBLE (2285 2360);
FORCEPROP 1 LASTPIN (2275 2350) BN 5
J 0
(2263 2358);
DISPLAY 0.680851 (2263 2358);
PAINT GREEN (2263 2358);
FORCEPROP 2 LAST CDS_LIB standard
J 0
(2325 2350);
DISPLAY INVISIBLE (2325 2350);
FORCEPROP 1 LAST BODY_TYPE PLUMBING
J 0
(2325 2400);
DISPLAY 0.872340 (2325 2400);
PAINT GREEN (2325 2400);
DISPLAY INVISIBLE (2325 2400);
FORCEPROP 1 LAST HDL_TAP TRUE
J 0
(2650 2225);
DISPLAY 0.872340 (2650 2225);
DISPLAY INVISIBLE (2650 2225);
FORCEPROP 1 LAST PATH I130
J 0
(2323 2350);
DISPLAY 0.872340 (2323 2350);
PAINT GREEN (2323 2350);
DISPLAY INVISIBLE (2323 2350);
FORCEADD TAP..1
(2325 2400);
FORCEPROP 3 LASTPIN (2275 2400) SIG_NAME M_A_CPU1_SB_DQS_DN<6>
J 0
(2285 2410);
DISPLAY 0.659574 (2285 2410);
PAINT MONO (2285 2410);
DISPLAY INVISIBLE (2285 2410);
FORCEPROP 1 LASTPIN (2275 2400) BN 6
J 0
(2263 2408);
DISPLAY 0.680851 (2263 2408);
PAINT GREEN (2263 2408);
FORCEPROP 2 LAST CDS_LIB standard
J 0
(2325 2400);
DISPLAY INVISIBLE (2325 2400);
FORCEPROP 1 LAST BODY_TYPE PLUMBING
J 0
(2325 2450);
DISPLAY 0.872340 (2325 2450);
PAINT GREEN (2325 2450);
DISPLAY INVISIBLE (2325 2450);
FORCEPROP 1 LAST HDL_TAP TRUE
J 0
(2650 2275);
DISPLAY 0.872340 (2650 2275);
DISPLAY INVISIBLE (2650 2275);
FORCEPROP 1 LAST PATH I131
J 0
(2323 2400);
DISPLAY 0.872340 (2323 2400);
PAINT GREEN (2323 2400);
DISPLAY INVISIBLE (2323 2400);
FORCEADD TAP..1
(2325 2450);
FORCEPROP 3 LASTPIN (2275 2450) SIG_NAME M_A_CPU1_SB_DQS_DN<7>
J 0
(2285 2460);
DISPLAY 0.659574 (2285 2460);
PAINT MONO (2285 2460);
DISPLAY INVISIBLE (2285 2460);
FORCEPROP 1 LASTPIN (2275 2450) BN 7
J 0
(2263 2458);
DISPLAY 0.680851 (2263 2458);
PAINT GREEN (2263 2458);
FORCEPROP 2 LAST CDS_LIB standard
J 0
(2325 2450);
DISPLAY INVISIBLE (2325 2450);
FORCEPROP 1 LAST BODY_TYPE PLUMBING
J 0
(2325 2500);
DISPLAY 0.872340 (2325 2500);
PAINT GREEN (2325 2500);
DISPLAY INVISIBLE (2325 2500);
FORCEPROP 1 LAST HDL_TAP TRUE
J 0
(2650 2325);
DISPLAY 0.872340 (2650 2325);
DISPLAY INVISIBLE (2650 2325);
FORCEPROP 1 LAST PATH I132
J 0
(2323 2450);
DISPLAY 0.872340 (2323 2450);
PAINT GREEN (2323 2450);
DISPLAY INVISIBLE (2323 2450);
FORCEADD TAP..1
(2325 2500);
FORCEPROP 3 LASTPIN (2275 2500) SIG_NAME M_A_CPU1_SB_DQS_DN<8>
J 0
(2285 2510);
DISPLAY 0.659574 (2285 2510);
PAINT MONO (2285 2510);
DISPLAY INVISIBLE (2285 2510);
FORCEPROP 1 LASTPIN (2275 2500) BN 8
J 0
(2263 2508);
DISPLAY 0.680851 (2263 2508);
PAINT GREEN (2263 2508);
FORCEPROP 2 LAST CDS_LIB standard
J 0
(2325 2500);
DISPLAY INVISIBLE (2325 2500);
FORCEPROP 1 LAST BODY_TYPE PLUMBING
J 0
(2325 2550);
DISPLAY 0.872340 (2325 2550);
PAINT GREEN (2325 2550);
DISPLAY INVISIBLE (2325 2550);
FORCEPROP 1 LAST HDL_TAP TRUE
J 0
(2650 2375);
DISPLAY 0.872340 (2650 2375);
DISPLAY INVISIBLE (2650 2375);
FORCEPROP 1 LAST PATH I133
J 0
(2323 2500);
DISPLAY 0.872340 (2323 2500);
PAINT GREEN (2323 2500);
DISPLAY INVISIBLE (2323 2500);
FORCEADD TAP..1
(2325 2550);
FORCEPROP 3 LASTPIN (2275 2550) SIG_NAME M_A_CPU1_SB_DQS_DN<9>
J 0
(2285 2560);
DISPLAY 0.659574 (2285 2560);
PAINT MONO (2285 2560);
DISPLAY INVISIBLE (2285 2560);
FORCEPROP 1 LASTPIN (2275 2550) BN 9
J 0
(2263 2558);
DISPLAY 0.680851 (2263 2558);
PAINT GREEN (2263 2558);
FORCEPROP 2 LAST CDS_LIB standard
J 0
(2325 2550);
DISPLAY INVISIBLE (2325 2550);
FORCEPROP 1 LAST BODY_TYPE PLUMBING
J 0
(2325 2600);
DISPLAY 0.872340 (2325 2600);
PAINT GREEN (2325 2600);
DISPLAY INVISIBLE (2325 2600);
FORCEPROP 1 LAST HDL_TAP TRUE
J 0
(2650 2425);
DISPLAY 0.872340 (2650 2425);
DISPLAY INVISIBLE (2650 2425);
FORCEPROP 1 LAST PATH I134
J 0
(2323 2550);
DISPLAY 0.872340 (2323 2550);
PAINT GREEN (2323 2550);
DISPLAY INVISIBLE (2323 2550);
FORCEADD TAP..1
(2325 2650);
FORCEPROP 3 LASTPIN (2275 2650) SIG_NAME M_A_CPU1_SB_DQS_DP<0>
J 0
(2285 2660);
DISPLAY 0.659574 (2285 2660);
PAINT MONO (2285 2660);
DISPLAY INVISIBLE (2285 2660);
FORCEPROP 1 LASTPIN (2275 2650) BN 0
J 0
(2263 2658);
DISPLAY 0.680851 (2263 2658);
PAINT GREEN (2263 2658);
FORCEPROP 2 LAST CDS_LIB standard
J 0
(2325 2650);
DISPLAY INVISIBLE (2325 2650);
FORCEPROP 1 LAST BODY_TYPE PLUMBING
J 0
(2325 2700);
DISPLAY 0.872340 (2325 2700);
PAINT GREEN (2325 2700);
DISPLAY INVISIBLE (2325 2700);
FORCEPROP 1 LAST HDL_TAP TRUE
J 0
(2650 2525);
DISPLAY 0.872340 (2650 2525);
DISPLAY INVISIBLE (2650 2525);
FORCEPROP 1 LAST PATH I135
J 0
(2323 2650);
DISPLAY 0.872340 (2323 2650);
PAINT GREEN (2323 2650);
DISPLAY INVISIBLE (2323 2650);
FORCEADD TAP..1
(2325 2700);
FORCEPROP 3 LASTPIN (2275 2700) SIG_NAME M_A_CPU1_SB_DQS_DP<1>
J 0
(2285 2710);
DISPLAY 0.659574 (2285 2710);
PAINT MONO (2285 2710);
DISPLAY INVISIBLE (2285 2710);
FORCEPROP 1 LASTPIN (2275 2700) BN 1
J 0
(2263 2708);
DISPLAY 0.680851 (2263 2708);
PAINT GREEN (2263 2708);
FORCEPROP 2 LAST CDS_LIB standard
J 0
(2325 2700);
DISPLAY INVISIBLE (2325 2700);
FORCEPROP 1 LAST BODY_TYPE PLUMBING
J 0
(2325 2750);
DISPLAY 0.872340 (2325 2750);
PAINT GREEN (2325 2750);
DISPLAY INVISIBLE (2325 2750);
FORCEPROP 1 LAST HDL_TAP TRUE
J 0
(2650 2575);
DISPLAY 0.872340 (2650 2575);
DISPLAY INVISIBLE (2650 2575);
FORCEPROP 1 LAST PATH I136
J 0
(2323 2700);
DISPLAY 0.872340 (2323 2700);
PAINT GREEN (2323 2700);
DISPLAY INVISIBLE (2323 2700);
FORCEADD TAP..1
(2325 2850);
FORCEPROP 3 LASTPIN (2275 2850) SIG_NAME M_A_CPU1_SB_DQS_DP<4>
J 0
(2285 2860);
DISPLAY 0.659574 (2285 2860);
PAINT MONO (2285 2860);
DISPLAY INVISIBLE (2285 2860);
FORCEPROP 1 LASTPIN (2275 2850) BN 4
J 0
(2263 2858);
DISPLAY 0.680851 (2263 2858);
PAINT GREEN (2263 2858);
FORCEPROP 2 LAST CDS_LIB standard
J 0
(2325 2850);
DISPLAY INVISIBLE (2325 2850);
FORCEPROP 1 LAST BODY_TYPE PLUMBING
J 0
(2325 2900);
DISPLAY 0.872340 (2325 2900);
PAINT GREEN (2325 2900);
DISPLAY INVISIBLE (2325 2900);
FORCEPROP 1 LAST HDL_TAP TRUE
J 0
(2650 2725);
DISPLAY 0.872340 (2650 2725);
DISPLAY INVISIBLE (2650 2725);
FORCEPROP 1 LAST PATH I137
J 0
(2323 2850);
DISPLAY 0.872340 (2323 2850);
PAINT GREEN (2323 2850);
DISPLAY INVISIBLE (2323 2850);
FORCEADD TAP..1
(2325 2750);
FORCEPROP 3 LASTPIN (2275 2750) SIG_NAME M_A_CPU1_SB_DQS_DP<2>
J 0
(2285 2760);
DISPLAY 0.659574 (2285 2760);
PAINT MONO (2285 2760);
DISPLAY INVISIBLE (2285 2760);
FORCEPROP 1 LASTPIN (2275 2750) BN 2
J 0
(2263 2758);
DISPLAY 0.680851 (2263 2758);
PAINT GREEN (2263 2758);
FORCEPROP 2 LAST CDS_LIB standard
J 0
(2325 2750);
DISPLAY INVISIBLE (2325 2750);
FORCEPROP 1 LAST BODY_TYPE PLUMBING
J 0
(2325 2800);
DISPLAY 0.872340 (2325 2800);
PAINT GREEN (2325 2800);
DISPLAY INVISIBLE (2325 2800);
FORCEPROP 1 LAST HDL_TAP TRUE
J 0
(2650 2625);
DISPLAY 0.872340 (2650 2625);
DISPLAY INVISIBLE (2650 2625);
FORCEPROP 1 LAST PATH I138
J 0
(2323 2750);
DISPLAY 0.872340 (2323 2750);
PAINT GREEN (2323 2750);
DISPLAY INVISIBLE (2323 2750);
FORCEADD TAP..1
(2325 2800);
FORCEPROP 3 LASTPIN (2275 2800) SIG_NAME M_A_CPU1_SB_DQS_DP<3>
J 0
(2285 2810);
DISPLAY 0.659574 (2285 2810);
PAINT MONO (2285 2810);
DISPLAY INVISIBLE (2285 2810);
FORCEPROP 1 LASTPIN (2275 2800) BN 3
J 0
(2263 2808);
DISPLAY 0.680851 (2263 2808);
PAINT GREEN (2263 2808);
FORCEPROP 2 LAST CDS_LIB standard
J 0
(2325 2800);
DISPLAY INVISIBLE (2325 2800);
FORCEPROP 1 LAST BODY_TYPE PLUMBING
J 0
(2325 2850);
DISPLAY 0.872340 (2325 2850);
PAINT GREEN (2325 2850);
DISPLAY INVISIBLE (2325 2850);
FORCEPROP 1 LAST HDL_TAP TRUE
J 0
(2650 2675);
DISPLAY 0.872340 (2650 2675);
DISPLAY INVISIBLE (2650 2675);
FORCEPROP 1 LAST PATH I139
J 0
(2323 2800);
DISPLAY 0.872340 (2323 2800);
PAINT GREEN (2323 2800);
DISPLAY INVISIBLE (2323 2800);
FORCEADD TAP..1
R 2
(-1100 550);
FORCEPROP 3 LASTPIN (-1050 550) SIG_NAME M_A_CPU1_SB_CB<5>
J 0
(-1040 560);
DISPLAY 0.659574 (-1040 560);
PAINT MONO (-1040 560);
DISPLAY INVISIBLE (-1040 560);
FORCEPROP 1 LASTPIN (-1050 550) BN 5
J 2
(-1038 558);
DISPLAY 0.680851 (-1038 558);
PAINT GREEN (-1038 558);
FORCEPROP 2 LAST CDS_LIB standard
J 0
(-1100 550);
DISPLAY INVISIBLE (-1100 550);
FORCEPROP 1 LAST BODY_TYPE PLUMBING
J 2
(-1100 600);
DISPLAY 0.872340 (-1100 600);
PAINT GREEN (-1100 600);
DISPLAY INVISIBLE (-1100 600);
FORCEPROP 1 LAST HDL_TAP TRUE
J 2
(-1425 425);
DISPLAY 0.872340 (-1425 425);
DISPLAY INVISIBLE (-1425 425);
FORCEPROP 1 LAST PATH I14
J 2
(-1098 550);
DISPLAY 0.872340 (-1098 550);
PAINT GREEN (-1098 550);
DISPLAY INVISIBLE (-1098 550);
FORCEADD TAP..1
(2325 2900);
FORCEPROP 3 LASTPIN (2275 2900) SIG_NAME M_A_CPU1_SB_DQS_DP<5>
J 0
(2285 2910);
DISPLAY 0.659574 (2285 2910);
PAINT MONO (2285 2910);
DISPLAY INVISIBLE (2285 2910);
FORCEPROP 1 LASTPIN (2275 2900) BN 5
J 0
(2263 2908);
DISPLAY 0.680851 (2263 2908);
PAINT GREEN (2263 2908);
FORCEPROP 2 LAST CDS_LIB standard
J 0
(2325 2900);
DISPLAY INVISIBLE (2325 2900);
FORCEPROP 1 LAST BODY_TYPE PLUMBING
J 0
(2325 2950);
DISPLAY 0.872340 (2325 2950);
PAINT GREEN (2325 2950);
DISPLAY INVISIBLE (2325 2950);
FORCEPROP 1 LAST HDL_TAP TRUE
J 0
(2650 2775);
DISPLAY 0.872340 (2650 2775);
DISPLAY INVISIBLE (2650 2775);
FORCEPROP 1 LAST PATH I140
J 0
(2323 2900);
DISPLAY 0.872340 (2323 2900);
PAINT GREEN (2323 2900);
DISPLAY INVISIBLE (2323 2900);
FORCEADD TAP..1
(2325 2950);
FORCEPROP 3 LASTPIN (2275 2950) SIG_NAME M_A_CPU1_SB_DQS_DP<6>
J 0
(2285 2960);
DISPLAY 0.659574 (2285 2960);
PAINT MONO (2285 2960);
DISPLAY INVISIBLE (2285 2960);
FORCEPROP 1 LASTPIN (2275 2950) BN 6
J 0
(2263 2958);
DISPLAY 0.680851 (2263 2958);
PAINT GREEN (2263 2958);
FORCEPROP 2 LAST CDS_LIB standard
J 0
(2325 2950);
DISPLAY INVISIBLE (2325 2950);
FORCEPROP 1 LAST BODY_TYPE PLUMBING
J 0
(2325 3000);
DISPLAY 0.872340 (2325 3000);
PAINT GREEN (2325 3000);
DISPLAY INVISIBLE (2325 3000);
FORCEPROP 1 LAST HDL_TAP TRUE
J 0
(2650 2825);
DISPLAY 0.872340 (2650 2825);
DISPLAY INVISIBLE (2650 2825);
FORCEPROP 1 LAST PATH I141
J 0
(2323 2950);
DISPLAY 0.872340 (2323 2950);
PAINT GREEN (2323 2950);
DISPLAY INVISIBLE (2323 2950);
FORCEADD TAP..1
(2325 3100);
FORCEPROP 3 LASTPIN (2275 3100) SIG_NAME M_A_CPU1_SB_DQS_DP<9>
J 0
(2285 3110);
DISPLAY 0.659574 (2285 3110);
PAINT MONO (2285 3110);
DISPLAY INVISIBLE (2285 3110);
FORCEPROP 1 LASTPIN (2275 3100) BN 9
J 0
(2263 3108);
DISPLAY 0.680851 (2263 3108);
PAINT GREEN (2263 3108);
FORCEPROP 2 LAST CDS_LIB standard
J 0
(2325 3100);
DISPLAY INVISIBLE (2325 3100);
FORCEPROP 1 LAST BODY_TYPE PLUMBING
J 0
(2325 3150);
DISPLAY 0.872340 (2325 3150);
PAINT GREEN (2325 3150);
DISPLAY INVISIBLE (2325 3150);
FORCEPROP 1 LAST HDL_TAP TRUE
J 0
(2650 2975);
DISPLAY 0.872340 (2650 2975);
DISPLAY INVISIBLE (2650 2975);
FORCEPROP 1 LAST PATH I142
J 0
(2323 3100);
DISPLAY 0.872340 (2323 3100);
PAINT GREEN (2323 3100);
DISPLAY INVISIBLE (2323 3100);
FORCEADD TAP..1
(2325 3050);
FORCEPROP 3 LASTPIN (2275 3050) SIG_NAME M_A_CPU1_SB_DQS_DP<8>
J 0
(2285 3060);
DISPLAY 0.659574 (2285 3060);
PAINT MONO (2285 3060);
DISPLAY INVISIBLE (2285 3060);
FORCEPROP 1 LASTPIN (2275 3050) BN 8
J 0
(2263 3058);
DISPLAY 0.680851 (2263 3058);
PAINT GREEN (2263 3058);
FORCEPROP 2 LAST CDS_LIB standard
J 0
(2325 3050);
DISPLAY INVISIBLE (2325 3050);
FORCEPROP 1 LAST BODY_TYPE PLUMBING
J 0
(2325 3100);
DISPLAY 0.872340 (2325 3100);
PAINT GREEN (2325 3100);
DISPLAY INVISIBLE (2325 3100);
FORCEPROP 1 LAST HDL_TAP TRUE
J 0
(2650 2925);
DISPLAY 0.872340 (2650 2925);
DISPLAY INVISIBLE (2650 2925);
FORCEPROP 1 LAST PATH I143
J 0
(2323 3050);
DISPLAY 0.872340 (2323 3050);
PAINT GREEN (2323 3050);
DISPLAY INVISIBLE (2323 3050);
FORCEADD TAP..1
(2325 3000);
FORCEPROP 3 LASTPIN (2275 3000) SIG_NAME M_A_CPU1_SB_DQS_DP<7>
J 0
(2285 3010);
DISPLAY 0.659574 (2285 3010);
PAINT MONO (2285 3010);
DISPLAY INVISIBLE (2285 3010);
FORCEPROP 1 LASTPIN (2275 3000) BN 7
J 0
(2263 3008);
DISPLAY 0.680851 (2263 3008);
PAINT GREEN (2263 3008);
FORCEPROP 2 LAST CDS_LIB standard
J 0
(2325 3000);
DISPLAY INVISIBLE (2325 3000);
FORCEPROP 1 LAST BODY_TYPE PLUMBING
J 0
(2325 3050);
DISPLAY 0.872340 (2325 3050);
PAINT GREEN (2325 3050);
DISPLAY INVISIBLE (2325 3050);
FORCEPROP 1 LAST HDL_TAP TRUE
J 0
(2650 2875);
DISPLAY 0.872340 (2650 2875);
DISPLAY INVISIBLE (2650 2875);
FORCEPROP 1 LAST PATH I144
J 0
(2323 3000);
DISPLAY 0.872340 (2323 3000);
PAINT GREEN (2323 3000);
DISPLAY INVISIBLE (2323 3000);
FORCEADD TAP..1
(2325 3250);
FORCEPROP 3 LASTPIN (2275 3250) SIG_NAME M_A_CPU1_SA_DQS_DN<0>
J 0
(2285 3260);
DISPLAY 0.659574 (2285 3260);
PAINT MONO (2285 3260);
DISPLAY INVISIBLE (2285 3260);
FORCEPROP 1 LASTPIN (2275 3250) BN 0
J 0
(2263 3258);
DISPLAY 0.680851 (2263 3258);
PAINT GREEN (2263 3258);
FORCEPROP 2 LAST CDS_LIB standard
J 0
(2325 3250);
DISPLAY INVISIBLE (2325 3250);
FORCEPROP 1 LAST BODY_TYPE PLUMBING
J 0
(2325 3300);
DISPLAY 0.872340 (2325 3300);
PAINT GREEN (2325 3300);
DISPLAY INVISIBLE (2325 3300);
FORCEPROP 1 LAST HDL_TAP TRUE
J 0
(2650 3125);
DISPLAY 0.872340 (2650 3125);
DISPLAY INVISIBLE (2650 3125);
FORCEPROP 1 LAST PATH I145
J 0
(2323 3250);
DISPLAY 0.872340 (2323 3250);
PAINT GREEN (2323 3250);
DISPLAY INVISIBLE (2323 3250);
FORCEADD TAP..1
(2325 3350);
FORCEPROP 3 LASTPIN (2275 3350) SIG_NAME M_A_CPU1_SA_DQS_DN<2>
J 0
(2285 3360);
DISPLAY 0.659574 (2285 3360);
PAINT MONO (2285 3360);
DISPLAY INVISIBLE (2285 3360);
FORCEPROP 1 LASTPIN (2275 3350) BN 2
J 0
(2263 3358);
DISPLAY 0.680851 (2263 3358);
PAINT GREEN (2263 3358);
FORCEPROP 2 LAST CDS_LIB standard
J 0
(2325 3350);
DISPLAY INVISIBLE (2325 3350);
FORCEPROP 1 LAST BODY_TYPE PLUMBING
J 0
(2325 3400);
DISPLAY 0.872340 (2325 3400);
PAINT GREEN (2325 3400);
DISPLAY INVISIBLE (2325 3400);
FORCEPROP 1 LAST HDL_TAP TRUE
J 0
(2650 3225);
DISPLAY 0.872340 (2650 3225);
DISPLAY INVISIBLE (2650 3225);
FORCEPROP 1 LAST PATH I146
J 0
(2323 3350);
DISPLAY 0.872340 (2323 3350);
PAINT GREEN (2323 3350);
DISPLAY INVISIBLE (2323 3350);
FORCEADD TAP..1
(2325 3300);
FORCEPROP 3 LASTPIN (2275 3300) SIG_NAME M_A_CPU1_SA_DQS_DN<1>
J 0
(2285 3310);
DISPLAY 0.659574 (2285 3310);
PAINT MONO (2285 3310);
DISPLAY INVISIBLE (2285 3310);
FORCEPROP 1 LASTPIN (2275 3300) BN 1
J 0
(2263 3308);
DISPLAY 0.680851 (2263 3308);
PAINT GREEN (2263 3308);
FORCEPROP 2 LAST CDS_LIB standard
J 0
(2325 3300);
DISPLAY INVISIBLE (2325 3300);
FORCEPROP 1 LAST BODY_TYPE PLUMBING
J 0
(2325 3350);
DISPLAY 0.872340 (2325 3350);
PAINT GREEN (2325 3350);
DISPLAY INVISIBLE (2325 3350);
FORCEPROP 1 LAST HDL_TAP TRUE
J 0
(2650 3175);
DISPLAY 0.872340 (2650 3175);
DISPLAY INVISIBLE (2650 3175);
FORCEPROP 1 LAST PATH I147
J 0
(2323 3300);
DISPLAY 0.872340 (2323 3300);
PAINT GREEN (2323 3300);
DISPLAY INVISIBLE (2323 3300);
FORCEADD TAP..1
(2325 3400);
FORCEPROP 3 LASTPIN (2275 3400) SIG_NAME M_A_CPU1_SA_DQS_DN<3>
J 0
(2285 3410);
DISPLAY 0.659574 (2285 3410);
PAINT MONO (2285 3410);
DISPLAY INVISIBLE (2285 3410);
FORCEPROP 1 LASTPIN (2275 3400) BN 3
J 0
(2263 3408);
DISPLAY 0.680851 (2263 3408);
PAINT GREEN (2263 3408);
FORCEPROP 2 LAST CDS_LIB standard
J 0
(2325 3400);
DISPLAY INVISIBLE (2325 3400);
FORCEPROP 1 LAST BODY_TYPE PLUMBING
J 0
(2325 3450);
DISPLAY 0.872340 (2325 3450);
PAINT GREEN (2325 3450);
DISPLAY INVISIBLE (2325 3450);
FORCEPROP 1 LAST HDL_TAP TRUE
J 0
(2650 3275);
DISPLAY 0.872340 (2650 3275);
DISPLAY INVISIBLE (2650 3275);
FORCEPROP 1 LAST PATH I148
J 0
(2323 3400);
DISPLAY 0.872340 (2323 3400);
PAINT GREEN (2323 3400);
DISPLAY INVISIBLE (2323 3400);
FORCEADD TAP..1
(2325 3500);
FORCEPROP 3 LASTPIN (2275 3500) SIG_NAME M_A_CPU1_SA_DQS_DN<5>
J 0
(2285 3510);
DISPLAY 0.659574 (2285 3510);
PAINT MONO (2285 3510);
DISPLAY INVISIBLE (2285 3510);
FORCEPROP 1 LASTPIN (2275 3500) BN 5
J 0
(2263 3508);
DISPLAY 0.680851 (2263 3508);
PAINT GREEN (2263 3508);
FORCEPROP 2 LAST CDS_LIB standard
J 0
(2325 3500);
DISPLAY INVISIBLE (2325 3500);
FORCEPROP 1 LAST BODY_TYPE PLUMBING
J 0
(2325 3550);
DISPLAY 0.872340 (2325 3550);
PAINT GREEN (2325 3550);
DISPLAY INVISIBLE (2325 3550);
FORCEPROP 1 LAST HDL_TAP TRUE
J 0
(2650 3375);
DISPLAY 0.872340 (2650 3375);
DISPLAY INVISIBLE (2650 3375);
FORCEPROP 1 LAST PATH I149
J 0
(2323 3500);
DISPLAY 0.872340 (2323 3500);
PAINT GREEN (2323 3500);
DISPLAY INVISIBLE (2323 3500);
FORCEADD TAP..1
R 2
(-1100 600);
FORCEPROP 3 LASTPIN (-1050 600) SIG_NAME M_A_CPU1_SB_CB<6>
J 0
(-1040 610);
DISPLAY 0.659574 (-1040 610);
PAINT MONO (-1040 610);
DISPLAY INVISIBLE (-1040 610);
FORCEPROP 1 LASTPIN (-1050 600) BN 6
J 2
(-1038 608);
DISPLAY 0.680851 (-1038 608);
PAINT GREEN (-1038 608);
FORCEPROP 2 LAST CDS_LIB standard
J 0
(-1100 600);
DISPLAY INVISIBLE (-1100 600);
FORCEPROP 1 LAST BODY_TYPE PLUMBING
J 2
(-1100 650);
DISPLAY 0.872340 (-1100 650);
PAINT GREEN (-1100 650);
DISPLAY INVISIBLE (-1100 650);
FORCEPROP 1 LAST HDL_TAP TRUE
J 2
(-1425 475);
DISPLAY 0.872340 (-1425 475);
DISPLAY INVISIBLE (-1425 475);
FORCEPROP 1 LAST PATH I15
J 2
(-1098 600);
DISPLAY 0.872340 (-1098 600);
PAINT GREEN (-1098 600);
DISPLAY INVISIBLE (-1098 600);
FORCEADD TAP..1
(2325 3450);
FORCEPROP 3 LASTPIN (2275 3450) SIG_NAME M_A_CPU1_SA_DQS_DN<4>
J 0
(2285 3460);
DISPLAY 0.659574 (2285 3460);
PAINT MONO (2285 3460);
DISPLAY INVISIBLE (2285 3460);
FORCEPROP 1 LASTPIN (2275 3450) BN 4
J 0
(2263 3458);
DISPLAY 0.680851 (2263 3458);
PAINT GREEN (2263 3458);
FORCEPROP 2 LAST CDS_LIB standard
J 0
(2325 3450);
DISPLAY INVISIBLE (2325 3450);
FORCEPROP 1 LAST BODY_TYPE PLUMBING
J 0
(2325 3500);
DISPLAY 0.872340 (2325 3500);
PAINT GREEN (2325 3500);
DISPLAY INVISIBLE (2325 3500);
FORCEPROP 1 LAST HDL_TAP TRUE
J 0
(2650 3325);
DISPLAY 0.872340 (2650 3325);
DISPLAY INVISIBLE (2650 3325);
FORCEPROP 1 LAST PATH I150
J 0
(2323 3450);
DISPLAY 0.872340 (2323 3450);
PAINT GREEN (2323 3450);
DISPLAY INVISIBLE (2323 3450);
FORCEADD TAP..1
(2325 3600);
FORCEPROP 3 LASTPIN (2275 3600) SIG_NAME M_A_CPU1_SA_DQS_DN<7>
J 0
(2285 3610);
DISPLAY 0.659574 (2285 3610);
PAINT MONO (2285 3610);
DISPLAY INVISIBLE (2285 3610);
FORCEPROP 1 LASTPIN (2275 3600) BN 7
J 0
(2263 3608);
DISPLAY 0.680851 (2263 3608);
PAINT GREEN (2263 3608);
FORCEPROP 2 LAST CDS_LIB standard
J 0
(2325 3600);
DISPLAY INVISIBLE (2325 3600);
FORCEPROP 1 LAST BODY_TYPE PLUMBING
J 0
(2325 3650);
DISPLAY 0.872340 (2325 3650);
PAINT GREEN (2325 3650);
DISPLAY INVISIBLE (2325 3650);
FORCEPROP 1 LAST HDL_TAP TRUE
J 0
(2650 3475);
DISPLAY 0.872340 (2650 3475);
DISPLAY INVISIBLE (2650 3475);
FORCEPROP 1 LAST PATH I151
J 0
(2323 3600);
DISPLAY 0.872340 (2323 3600);
PAINT GREEN (2323 3600);
DISPLAY INVISIBLE (2323 3600);
FORCEADD TAP..1
(2325 3550);
FORCEPROP 3 LASTPIN (2275 3550) SIG_NAME M_A_CPU1_SA_DQS_DN<6>
J 0
(2285 3560);
DISPLAY 0.659574 (2285 3560);
PAINT MONO (2285 3560);
DISPLAY INVISIBLE (2285 3560);
FORCEPROP 1 LASTPIN (2275 3550) BN 6
J 0
(2263 3558);
DISPLAY 0.680851 (2263 3558);
PAINT GREEN (2263 3558);
FORCEPROP 2 LAST CDS_LIB standard
J 0
(2325 3550);
DISPLAY INVISIBLE (2325 3550);
FORCEPROP 1 LAST BODY_TYPE PLUMBING
J 0
(2325 3600);
DISPLAY 0.872340 (2325 3600);
PAINT GREEN (2325 3600);
DISPLAY INVISIBLE (2325 3600);
FORCEPROP 1 LAST HDL_TAP TRUE
J 0
(2650 3425);
DISPLAY 0.872340 (2650 3425);
DISPLAY INVISIBLE (2650 3425);
FORCEPROP 1 LAST PATH I152
J 0
(2323 3550);
DISPLAY 0.872340 (2323 3550);
PAINT GREEN (2323 3550);
DISPLAY INVISIBLE (2323 3550);
FORCEADD TAP..1
(2325 3700);
FORCEPROP 3 LASTPIN (2275 3700) SIG_NAME M_A_CPU1_SA_DQS_DN<9>
J 0
(2285 3710);
DISPLAY 0.659574 (2285 3710);
PAINT MONO (2285 3710);
DISPLAY INVISIBLE (2285 3710);
FORCEPROP 1 LASTPIN (2275 3700) BN 9
J 0
(2263 3708);
DISPLAY 0.680851 (2263 3708);
PAINT GREEN (2263 3708);
FORCEPROP 2 LAST CDS_LIB standard
J 0
(2325 3700);
DISPLAY INVISIBLE (2325 3700);
FORCEPROP 1 LAST BODY_TYPE PLUMBING
J 0
(2325 3750);
DISPLAY 0.872340 (2325 3750);
PAINT GREEN (2325 3750);
DISPLAY INVISIBLE (2325 3750);
FORCEPROP 1 LAST HDL_TAP TRUE
J 0
(2650 3575);
DISPLAY 0.872340 (2650 3575);
DISPLAY INVISIBLE (2650 3575);
FORCEPROP 1 LAST PATH I153
J 0
(2323 3700);
DISPLAY 0.872340 (2323 3700);
PAINT GREEN (2323 3700);
DISPLAY INVISIBLE (2323 3700);
FORCEADD TAP..1
(2325 3650);
FORCEPROP 3 LASTPIN (2275 3650) SIG_NAME M_A_CPU1_SA_DQS_DN<8>
J 0
(2285 3660);
DISPLAY 0.659574 (2285 3660);
PAINT MONO (2285 3660);
DISPLAY INVISIBLE (2285 3660);
FORCEPROP 1 LASTPIN (2275 3650) BN 8
J 0
(2263 3658);
DISPLAY 0.680851 (2263 3658);
PAINT GREEN (2263 3658);
FORCEPROP 2 LAST CDS_LIB standard
J 0
(2325 3650);
DISPLAY INVISIBLE (2325 3650);
FORCEPROP 1 LAST BODY_TYPE PLUMBING
J 0
(2325 3700);
DISPLAY 0.872340 (2325 3700);
PAINT GREEN (2325 3700);
DISPLAY INVISIBLE (2325 3700);
FORCEPROP 1 LAST HDL_TAP TRUE
J 0
(2650 3525);
DISPLAY 0.872340 (2650 3525);
DISPLAY INVISIBLE (2650 3525);
FORCEPROP 1 LAST PATH I154
J 0
(2323 3650);
DISPLAY 0.872340 (2323 3650);
PAINT GREEN (2323 3650);
DISPLAY INVISIBLE (2323 3650);
FORCEADD TAP..1
(2325 3850);
FORCEPROP 3 LASTPIN (2275 3850) SIG_NAME M_A_CPU1_SA_DQS_DP<1>
J 0
(2285 3860);
DISPLAY 0.659574 (2285 3860);
PAINT MONO (2285 3860);
DISPLAY INVISIBLE (2285 3860);
FORCEPROP 1 LASTPIN (2275 3850) BN 1
J 0
(2263 3858);
DISPLAY 0.680851 (2263 3858);
PAINT GREEN (2263 3858);
FORCEPROP 2 LAST CDS_LIB standard
J 0
(2325 3850);
DISPLAY INVISIBLE (2325 3850);
FORCEPROP 1 LAST BODY_TYPE PLUMBING
J 0
(2325 3900);
DISPLAY 0.872340 (2325 3900);
PAINT GREEN (2325 3900);
DISPLAY INVISIBLE (2325 3900);
FORCEPROP 1 LAST HDL_TAP TRUE
J 0
(2650 3725);
DISPLAY 0.872340 (2650 3725);
DISPLAY INVISIBLE (2650 3725);
FORCEPROP 1 LAST PATH I155
J 0
(2323 3850);
DISPLAY 0.872340 (2323 3850);
PAINT GREEN (2323 3850);
DISPLAY INVISIBLE (2323 3850);
FORCEADD TAP..1
(2325 3800);
FORCEPROP 3 LASTPIN (2275 3800) SIG_NAME M_A_CPU1_SA_DQS_DP<0>
J 0
(2285 3810);
DISPLAY 0.659574 (2285 3810);
PAINT MONO (2285 3810);
DISPLAY INVISIBLE (2285 3810);
FORCEPROP 1 LASTPIN (2275 3800) BN 0
J 0
(2263 3808);
DISPLAY 0.680851 (2263 3808);
PAINT GREEN (2263 3808);
FORCEPROP 2 LAST CDS_LIB standard
J 0
(2325 3800);
DISPLAY INVISIBLE (2325 3800);
FORCEPROP 1 LAST BODY_TYPE PLUMBING
J 0
(2325 3850);
DISPLAY 0.872340 (2325 3850);
PAINT GREEN (2325 3850);
DISPLAY INVISIBLE (2325 3850);
FORCEPROP 1 LAST HDL_TAP TRUE
J 0
(2650 3675);
DISPLAY 0.872340 (2650 3675);
DISPLAY INVISIBLE (2650 3675);
FORCEPROP 1 LAST PATH I156
J 0
(2323 3800);
DISPLAY 0.872340 (2323 3800);
PAINT GREEN (2323 3800);
DISPLAY INVISIBLE (2323 3800);
FORCEADD TAP..1
(2325 3900);
FORCEPROP 3 LASTPIN (2275 3900) SIG_NAME M_A_CPU1_SA_DQS_DP<2>
J 0
(2285 3910);
DISPLAY 0.659574 (2285 3910);
PAINT MONO (2285 3910);
DISPLAY INVISIBLE (2285 3910);
FORCEPROP 1 LASTPIN (2275 3900) BN 2
J 0
(2263 3908);
DISPLAY 0.680851 (2263 3908);
PAINT GREEN (2263 3908);
FORCEPROP 2 LAST CDS_LIB standard
J 0
(2325 3900);
DISPLAY INVISIBLE (2325 3900);
FORCEPROP 1 LAST BODY_TYPE PLUMBING
J 0
(2325 3950);
DISPLAY 0.872340 (2325 3950);
PAINT GREEN (2325 3950);
DISPLAY INVISIBLE (2325 3950);
FORCEPROP 1 LAST HDL_TAP TRUE
J 0
(2650 3775);
DISPLAY 0.872340 (2650 3775);
DISPLAY INVISIBLE (2650 3775);
FORCEPROP 1 LAST PATH I157
J 0
(2323 3900);
DISPLAY 0.872340 (2323 3900);
PAINT GREEN (2323 3900);
DISPLAY INVISIBLE (2323 3900);
FORCEADD TAP..1
(2325 3950);
FORCEPROP 3 LASTPIN (2275 3950) SIG_NAME M_A_CPU1_SA_DQS_DP<3>
J 0
(2285 3960);
DISPLAY 0.659574 (2285 3960);
PAINT MONO (2285 3960);
DISPLAY INVISIBLE (2285 3960);
FORCEPROP 1 LASTPIN (2275 3950) BN 3
J 0
(2263 3958);
DISPLAY 0.680851 (2263 3958);
PAINT GREEN (2263 3958);
FORCEPROP 2 LAST CDS_LIB standard
J 0
(2325 3950);
DISPLAY INVISIBLE (2325 3950);
FORCEPROP 1 LAST BODY_TYPE PLUMBING
J 0
(2325 4000);
DISPLAY 0.872340 (2325 4000);
PAINT GREEN (2325 4000);
DISPLAY INVISIBLE (2325 4000);
FORCEPROP 1 LAST HDL_TAP TRUE
J 0
(2650 3825);
DISPLAY 0.872340 (2650 3825);
DISPLAY INVISIBLE (2650 3825);
FORCEPROP 1 LAST PATH I158
J 0
(2323 3950);
DISPLAY 0.872340 (2323 3950);
PAINT GREEN (2323 3950);
DISPLAY INVISIBLE (2323 3950);
FORCEADD TAP..1
(2325 4000);
FORCEPROP 3 LASTPIN (2275 4000) SIG_NAME M_A_CPU1_SA_DQS_DP<4>
J 0
(2285 4010);
DISPLAY 0.659574 (2285 4010);
PAINT MONO (2285 4010);
DISPLAY INVISIBLE (2285 4010);
FORCEPROP 1 LASTPIN (2275 4000) BN 4
J 0
(2263 4008);
DISPLAY 0.680851 (2263 4008);
PAINT GREEN (2263 4008);
FORCEPROP 2 LAST CDS_LIB standard
J 0
(2325 4000);
DISPLAY INVISIBLE (2325 4000);
FORCEPROP 1 LAST BODY_TYPE PLUMBING
J 0
(2325 4050);
DISPLAY 0.872340 (2325 4050);
PAINT GREEN (2325 4050);
DISPLAY INVISIBLE (2325 4050);
FORCEPROP 1 LAST HDL_TAP TRUE
J 0
(2650 3875);
DISPLAY 0.872340 (2650 3875);
DISPLAY INVISIBLE (2650 3875);
FORCEPROP 1 LAST PATH I159
J 0
(2323 4000);
DISPLAY 0.872340 (2323 4000);
PAINT GREEN (2323 4000);
DISPLAY INVISIBLE (2323 4000);
FORCEADD TAP..1
R 2
(-1100 650);
FORCEPROP 3 LASTPIN (-1050 650) SIG_NAME M_A_CPU1_SB_CB<7>
J 0
(-1040 660);
DISPLAY 0.659574 (-1040 660);
PAINT MONO (-1040 660);
DISPLAY INVISIBLE (-1040 660);
FORCEPROP 1 LASTPIN (-1050 650) BN 7
J 2
(-1038 658);
DISPLAY 0.680851 (-1038 658);
PAINT GREEN (-1038 658);
FORCEPROP 2 LAST CDS_LIB standard
J 0
(-1100 650);
DISPLAY INVISIBLE (-1100 650);
FORCEPROP 1 LAST BODY_TYPE PLUMBING
J 2
(-1100 700);
DISPLAY 0.872340 (-1100 700);
PAINT GREEN (-1100 700);
DISPLAY INVISIBLE (-1100 700);
FORCEPROP 1 LAST HDL_TAP TRUE
J 2
(-1425 525);
DISPLAY 0.872340 (-1425 525);
DISPLAY INVISIBLE (-1425 525);
FORCEPROP 1 LAST PATH I16
J 2
(-1098 650);
DISPLAY 0.872340 (-1098 650);
PAINT GREEN (-1098 650);
DISPLAY INVISIBLE (-1098 650);
FORCEADD TAP..1
(2325 4050);
FORCEPROP 3 LASTPIN (2275 4050) SIG_NAME M_A_CPU1_SA_DQS_DP<5>
J 0
(2285 4060);
DISPLAY 0.659574 (2285 4060);
PAINT MONO (2285 4060);
DISPLAY INVISIBLE (2285 4060);
FORCEPROP 1 LASTPIN (2275 4050) BN 5
J 0
(2263 4058);
DISPLAY 0.680851 (2263 4058);
PAINT GREEN (2263 4058);
FORCEPROP 2 LAST CDS_LIB standard
J 0
(2325 4050);
DISPLAY INVISIBLE (2325 4050);
FORCEPROP 1 LAST BODY_TYPE PLUMBING
J 0
(2325 4100);
DISPLAY 0.872340 (2325 4100);
PAINT GREEN (2325 4100);
DISPLAY INVISIBLE (2325 4100);
FORCEPROP 1 LAST HDL_TAP TRUE
J 0
(2650 3925);
DISPLAY 0.872340 (2650 3925);
DISPLAY INVISIBLE (2650 3925);
FORCEPROP 1 LAST PATH I160
J 0
(2323 4050);
DISPLAY 0.872340 (2323 4050);
PAINT GREEN (2323 4050);
DISPLAY INVISIBLE (2323 4050);
FORCEADD TAP..1
(2325 4100);
FORCEPROP 3 LASTPIN (2275 4100) SIG_NAME M_A_CPU1_SA_DQS_DP<6>
J 0
(2285 4110);
DISPLAY 0.659574 (2285 4110);
PAINT MONO (2285 4110);
DISPLAY INVISIBLE (2285 4110);
FORCEPROP 1 LASTPIN (2275 4100) BN 6
J 0
(2263 4108);
DISPLAY 0.680851 (2263 4108);
PAINT GREEN (2263 4108);
FORCEPROP 2 LAST CDS_LIB standard
J 0
(2325 4100);
DISPLAY INVISIBLE (2325 4100);
FORCEPROP 1 LAST BODY_TYPE PLUMBING
J 0
(2325 4150);
DISPLAY 0.872340 (2325 4150);
PAINT GREEN (2325 4150);
DISPLAY INVISIBLE (2325 4150);
FORCEPROP 1 LAST HDL_TAP TRUE
J 0
(2650 3975);
DISPLAY 0.872340 (2650 3975);
DISPLAY INVISIBLE (2650 3975);
FORCEPROP 1 LAST PATH I161
J 0
(2323 4100);
DISPLAY 0.872340 (2323 4100);
PAINT GREEN (2323 4100);
DISPLAY INVISIBLE (2323 4100);
FORCEADD OFFPAGE..3
(3425 2575);
FORCEPROP 2 LAST $XR1 99 
J 0
(3729 2575);
DISPLAY 0.638298 (3729 2575);
PAINT MONO (3729 2575);
FORCEPROP 2 LAST $XR0 98 
J 0
(3639 2575);
DISPLAY 0.638298 (3639 2575);
PAINT MONO (3639 2575);
FORCEPROP 2 LAST CDS_LIB standard
J 2
(3425 2575);
DISPLAY INVISIBLE (3425 2575);
FORCEPROP 1 LAST OFFPAGE TRUE
J 0
(3750 2450);
DISPLAY 0.872340 (3750 2450);
DISPLAY INVISIBLE (3750 2450);
FORCEPROP 1 LAST COMMENT_BODY TRUE
J 0
(3375 2475);
DISPLAY 0.872340 (3375 2475);
PAINT GREEN (3375 2475);
DISPLAY INVISIBLE (3375 2475);
FORCEPROP 2 LAST PATH I162
J 0
(3625 2650);
DISPLAY 1.021277 (3625 2650);
DISPLAY INVISIBLE (3625 2650);
FORCEADD OFFPAGE..3
(3425 3125);
FORCEPROP 2 LAST $XR1 99 
J 0
(3729 3125);
DISPLAY 0.638298 (3729 3125);
PAINT MONO (3729 3125);
FORCEPROP 2 LAST $XR0 98 
J 0
(3639 3125);
DISPLAY 0.638298 (3639 3125);
PAINT MONO (3639 3125);
FORCEPROP 2 LAST CDS_LIB standard
J 2
(3425 3125);
DISPLAY INVISIBLE (3425 3125);
FORCEPROP 1 LAST OFFPAGE TRUE
J 0
(3750 3000);
DISPLAY 0.872340 (3750 3000);
DISPLAY INVISIBLE (3750 3000);
FORCEPROP 1 LAST COMMENT_BODY TRUE
J 0
(3375 3025);
DISPLAY 0.872340 (3375 3025);
PAINT GREEN (3375 3025);
DISPLAY INVISIBLE (3375 3025);
FORCEPROP 2 LAST PATH I163
J 0
(3625 3200);
DISPLAY 1.021277 (3625 3200);
DISPLAY INVISIBLE (3625 3200);
FORCEADD OFFPAGE..3
(3425 3725);
FORCEPROP 2 LAST $XR1 99 
J 0
(3729 3725);
DISPLAY 0.638298 (3729 3725);
PAINT MONO (3729 3725);
FORCEPROP 2 LAST $XR0 98 
J 0
(3639 3725);
DISPLAY 0.638298 (3639 3725);
PAINT MONO (3639 3725);
FORCEPROP 2 LAST CDS_LIB standard
J 2
(3425 3725);
DISPLAY INVISIBLE (3425 3725);
FORCEPROP 1 LAST OFFPAGE TRUE
J 0
(3750 3600);
DISPLAY 0.872340 (3750 3600);
DISPLAY INVISIBLE (3750 3600);
FORCEPROP 1 LAST COMMENT_BODY TRUE
J 0
(3375 3625);
DISPLAY 0.872340 (3375 3625);
PAINT GREEN (3375 3625);
DISPLAY INVISIBLE (3375 3625);
FORCEPROP 2 LAST PATH I164
J 0
(3625 3800);
DISPLAY 1.021277 (3625 3800);
DISPLAY INVISIBLE (3625 3800);
FORCEADD TAP..1
(2325 4250);
FORCEPROP 3 LASTPIN (2275 4250) SIG_NAME M_A_CPU1_SA_DQS_DP<9>
J 0
(2285 4260);
DISPLAY 0.659574 (2285 4260);
PAINT MONO (2285 4260);
DISPLAY INVISIBLE (2285 4260);
FORCEPROP 1 LASTPIN (2275 4250) BN 9
J 0
(2263 4258);
DISPLAY 0.680851 (2263 4258);
PAINT GREEN (2263 4258);
FORCEPROP 2 LAST CDS_LIB standard
J 0
(2325 4250);
DISPLAY INVISIBLE (2325 4250);
FORCEPROP 1 LAST BODY_TYPE PLUMBING
J 0
(2325 4300);
DISPLAY 0.872340 (2325 4300);
PAINT GREEN (2325 4300);
DISPLAY INVISIBLE (2325 4300);
FORCEPROP 1 LAST HDL_TAP TRUE
J 0
(2650 4125);
DISPLAY 0.872340 (2650 4125);
DISPLAY INVISIBLE (2650 4125);
FORCEPROP 1 LAST PATH I165
J 0
(2323 4250);
DISPLAY 0.872340 (2323 4250);
PAINT GREEN (2323 4250);
DISPLAY INVISIBLE (2323 4250);
FORCEADD TAP..1
(2325 4200);
FORCEPROP 3 LASTPIN (2275 4200) SIG_NAME M_A_CPU1_SA_DQS_DP<8>
J 0
(2285 4210);
DISPLAY 0.659574 (2285 4210);
PAINT MONO (2285 4210);
DISPLAY INVISIBLE (2285 4210);
FORCEPROP 1 LASTPIN (2275 4200) BN 8
J 0
(2263 4208);
DISPLAY 0.680851 (2263 4208);
PAINT GREEN (2263 4208);
FORCEPROP 2 LAST CDS_LIB standard
J 0
(2325 4200);
DISPLAY INVISIBLE (2325 4200);
FORCEPROP 1 LAST BODY_TYPE PLUMBING
J 0
(2325 4250);
DISPLAY 0.872340 (2325 4250);
PAINT GREEN (2325 4250);
DISPLAY INVISIBLE (2325 4250);
FORCEPROP 1 LAST HDL_TAP TRUE
J 0
(2650 4075);
DISPLAY 0.872340 (2650 4075);
DISPLAY INVISIBLE (2650 4075);
FORCEPROP 1 LAST PATH I166
J 0
(2323 4200);
DISPLAY 0.872340 (2323 4200);
PAINT GREEN (2323 4200);
DISPLAY INVISIBLE (2323 4200);
FORCEADD TAP..1
(2325 4150);
FORCEPROP 3 LASTPIN (2275 4150) SIG_NAME M_A_CPU1_SA_DQS_DP<7>
J 0
(2285 4160);
DISPLAY 0.659574 (2285 4160);
PAINT MONO (2285 4160);
DISPLAY INVISIBLE (2285 4160);
FORCEPROP 1 LASTPIN (2275 4150) BN 7
J 0
(2263 4158);
DISPLAY 0.680851 (2263 4158);
PAINT GREEN (2263 4158);
FORCEPROP 2 LAST CDS_LIB standard
J 0
(2325 4150);
DISPLAY INVISIBLE (2325 4150);
FORCEPROP 1 LAST BODY_TYPE PLUMBING
J 0
(2325 4200);
DISPLAY 0.872340 (2325 4200);
PAINT GREEN (2325 4200);
DISPLAY INVISIBLE (2325 4200);
FORCEPROP 1 LAST HDL_TAP TRUE
J 0
(2650 4025);
DISPLAY 0.872340 (2650 4025);
DISPLAY INVISIBLE (2650 4025);
FORCEPROP 1 LAST PATH I167
J 0
(2323 4150);
DISPLAY 0.872340 (2323 4150);
PAINT GREEN (2323 4150);
DISPLAY INVISIBLE (2323 4150);
FORCEADD OFFPAGE..3
(3425 4275);
FORCEPROP 2 LAST $XR1 99 
J 0
(3729 4275);
DISPLAY 0.638298 (3729 4275);
PAINT MONO (3729 4275);
FORCEPROP 2 LAST $XR0 98 
J 0
(3639 4275);
DISPLAY 0.638298 (3639 4275);
PAINT MONO (3639 4275);
FORCEPROP 2 LAST CDS_LIB standard
J 2
(3425 4275);
DISPLAY INVISIBLE (3425 4275);
FORCEPROP 1 LAST OFFPAGE TRUE
J 0
(3750 4150);
DISPLAY 0.872340 (3750 4150);
DISPLAY INVISIBLE (3750 4150);
FORCEPROP 1 LAST COMMENT_BODY TRUE
J 0
(3375 4175);
DISPLAY 0.872340 (3375 4175);
PAINT GREEN (3375 4175);
DISPLAY INVISIBLE (3375 4175);
FORCEPROP 2 LAST PATH I168
J 0
(3625 4350);
DISPLAY 1.021277 (3625 4350);
DISPLAY INVISIBLE (3625 4350);
FORCEADD TAP..1
R 2
(-1100 750);
FORCEPROP 3 LASTPIN (-1050 750) SIG_NAME M_A_CPU1_SB_DQ<1>
J 0
(-1040 760);
DISPLAY 0.659574 (-1040 760);
PAINT MONO (-1040 760);
DISPLAY INVISIBLE (-1040 760);
FORCEPROP 1 LASTPIN (-1050 750) BN 1
J 2
(-1038 758);
DISPLAY 0.680851 (-1038 758);
PAINT GREEN (-1038 758);
FORCEPROP 2 LAST CDS_LIB standard
J 0
(-1100 750);
DISPLAY INVISIBLE (-1100 750);
FORCEPROP 1 LAST BODY_TYPE PLUMBING
J 2
(-1100 800);
DISPLAY 0.872340 (-1100 800);
PAINT GREEN (-1100 800);
DISPLAY INVISIBLE (-1100 800);
FORCEPROP 1 LAST HDL_TAP TRUE
J 2
(-1425 625);
DISPLAY 0.872340 (-1425 625);
DISPLAY INVISIBLE (-1425 625);
FORCEPROP 1 LAST PATH I17
J 2
(-1098 750);
DISPLAY 0.872340 (-1098 750);
PAINT GREEN (-1098 750);
DISPLAY INVISIBLE (-1098 750);
FORCEADD TAP..1
R 2
(-1100 700);
FORCEPROP 3 LASTPIN (-1050 700) SIG_NAME M_A_CPU1_SB_DQ<0>
J 0
(-1040 710);
DISPLAY 0.659574 (-1040 710);
PAINT MONO (-1040 710);
DISPLAY INVISIBLE (-1040 710);
FORCEPROP 1 LASTPIN (-1050 700) BN 0
J 2
(-1038 708);
DISPLAY 0.680851 (-1038 708);
PAINT GREEN (-1038 708);
FORCEPROP 2 LAST CDS_LIB standard
J 0
(-1100 700);
DISPLAY INVISIBLE (-1100 700);
FORCEPROP 1 LAST BODY_TYPE PLUMBING
J 2
(-1100 750);
DISPLAY 0.872340 (-1100 750);
PAINT GREEN (-1100 750);
DISPLAY INVISIBLE (-1100 750);
FORCEPROP 1 LAST HDL_TAP TRUE
J 2
(-1425 575);
DISPLAY 0.872340 (-1425 575);
DISPLAY INVISIBLE (-1425 575);
FORCEPROP 1 LAST PATH I18
J 2
(-1098 700);
DISPLAY 0.872340 (-1098 700);
PAINT GREEN (-1098 700);
DISPLAY INVISIBLE (-1098 700);
FORCEADD TAP..1
R 2
(-1100 800);
FORCEPROP 3 LASTPIN (-1050 800) SIG_NAME M_A_CPU1_SB_DQ<2>
J 0
(-1040 810);
DISPLAY 0.659574 (-1040 810);
PAINT MONO (-1040 810);
DISPLAY INVISIBLE (-1040 810);
FORCEPROP 1 LASTPIN (-1050 800) BN 2
J 2
(-1038 808);
DISPLAY 0.680851 (-1038 808);
PAINT GREEN (-1038 808);
FORCEPROP 2 LAST CDS_LIB standard
J 0
(-1100 800);
DISPLAY INVISIBLE (-1100 800);
FORCEPROP 1 LAST BODY_TYPE PLUMBING
J 2
(-1100 850);
DISPLAY 0.872340 (-1100 850);
PAINT GREEN (-1100 850);
DISPLAY INVISIBLE (-1100 850);
FORCEPROP 1 LAST HDL_TAP TRUE
J 2
(-1425 675);
DISPLAY 0.872340 (-1425 675);
DISPLAY INVISIBLE (-1425 675);
FORCEPROP 1 LAST PATH I19
J 2
(-1098 800);
DISPLAY 0.872340 (-1098 800);
PAINT GREEN (-1098 800);
DISPLAY INVISIBLE (-1098 800);
FORCEADD SOCKET4677_AZIF0045P001C01CS..8
(625 2150);
FORCEPROP 1 LAST PART_NUMBER DGA^7000023
J 0
(-475 4500);
DISPLAY 0.723404 (-475 4500);
PAINT GREEN (-475 4500);
DISPLAY INVISIBLE (-475 4500);
FORCEPROP 2 LAST PART_TYPE SMLF
J 0
(-475 4675);
DISPLAY 1.021277 (-475 4675);
FORCEPROP 1 LAST MATERIAL IO
J 0
(-475 4425);
DISPLAY 0.723404 (-475 4425);
PAINT GREEN (-475 4425);
FORCEPROP 2 LAST VALUE SOCKET4677_AZIF0045-P001C01CS
J 0
(-475 4625);
DISPLAY 1.021277 (-475 4625);
FORCEPROP 1 LAST $LOCATION U1
J 0
(-475 4575);
DISPLAY 0.723404 (-475 4575);
PAINT GREEN (-475 4575);
FORCEPROP 0 LASTPIN (1850 300) $PN AT42
J 0
(1860 310);
DISPLAY 0.680851 (1860 310);
PAINT MONO (1860 310);
FORCEPROP 0 LASTPIN (1850 350) $PN AU43
J 0
(1860 360);
DISPLAY 0.680851 (1860 360);
PAINT MONO (1860 360);
FORCEPROP 0 LASTPIN (1850 50) $PN AT49
J 0
(1860 60);
DISPLAY 0.680851 (1860 60);
PAINT MONO (1860 60);
FORCEPROP 0 LASTPIN (1850 150) $PN AV44
J 0
(1860 160);
DISPLAY 0.680851 (1860 160);
PAINT MONO (1860 160);
FORCEPROP 0 LASTPIN (1850 200) $PN AV42
J 0
(1860 210);
DISPLAY 0.680851 (1860 210);
PAINT MONO (1860 210);
FORCEPROP 0 LASTPIN (-600 50) $PN B44
J 2
(-610 60);
DISPLAY 0.680851 (-610 60);
PAINT MONO (-610 60);
FORCEPROP 0 LASTPIN (-600 100) $PN G45
J 2
(-610 110);
DISPLAY 0.680851 (-610 110);
PAINT MONO (-610 110);
FORCEPROP 0 LASTPIN (-600 150) $PN C43
J 2
(-610 160);
DISPLAY 0.680851 (-610 160);
PAINT MONO (-610 160);
FORCEPROP 0 LASTPIN (-600 200) $PN E45
J 2
(-610 210);
DISPLAY 0.680851 (-610 210);
PAINT MONO (-610 210);
FORCEPROP 0 LASTPIN (1850 1650) $PN A52
J 0
(1860 1660);
DISPLAY 0.680851 (1860 1660);
PAINT MONO (1860 1660);
FORCEPROP 0 LASTPIN (1850 1700) $PN G52
J 0
(1860 1710);
DISPLAY 0.680851 (1860 1710);
PAINT MONO (1860 1710);
FORCEPROP 0 LASTPIN (1850 1750) $PN B51
J 0
(1860 1760);
DISPLAY 0.680851 (1860 1760);
PAINT MONO (1860 1760);
FORCEPROP 0 LASTPIN (1850 1800) $PN F51
J 0
(1860 1810);
DISPLAY 0.680851 (1860 1810);
PAINT MONO (1860 1810);
FORCEPROP 0 LASTPIN (1850 1850) $PN C50
J 0
(1860 1860);
DISPLAY 0.680851 (1860 1860);
PAINT MONO (1860 1860);
FORCEPROP 0 LASTPIN (1850 1900) $PN E50
J 0
(1860 1910);
DISPLAY 0.680851 (1860 1910);
PAINT MONO (1860 1910);
FORCEPROP 0 LASTPIN (1850 1950) $PN C48
J 0
(1860 1960);
DISPLAY 0.680851 (1860 1960);
PAINT MONO (1860 1960);
FORCEPROP 0 LASTPIN (-600 2700) $PN B81
J 2
(-610 2710);
DISPLAY 0.680851 (-610 2710);
PAINT MONO (-610 2710);
FORCEPROP 0 LASTPIN (-600 2750) $PN B79
J 2
(-610 2760);
DISPLAY 0.680851 (-610 2760);
PAINT MONO (-610 2760);
FORCEPROP 0 LASTPIN (-600 2800) $PN M77
J 2
(-610 2810);
DISPLAY 0.680851 (-610 2810);
PAINT MONO (-610 2810);
FORCEPROP 0 LASTPIN (-600 2850) $PN G78
J 2
(-610 2860);
DISPLAY 0.680851 (-610 2860);
PAINT MONO (-610 2860);
FORCEPROP 0 LASTPIN (-600 2900) $PN C76
J 2
(-610 2910);
DISPLAY 0.680851 (-610 2910);
PAINT MONO (-610 2910);
FORCEPROP 0 LASTPIN (-600 2950) $PN D75
J 2
(-610 2960);
DISPLAY 0.680851 (-610 2960);
PAINT MONO (-610 2960);
FORCEPROP 0 LASTPIN (-600 3000) $PN G76
J 2
(-610 3010);
DISPLAY 0.680851 (-610 3010);
PAINT MONO (-610 3010);
FORCEPROP 0 LASTPIN (-600 3050) $PN F75
J 2
(-610 3060);
DISPLAY 0.680851 (-610 3060);
PAINT MONO (-610 3060);
FORCEPROP 0 LASTPIN (-600 3100) $PN K69
J 2
(-610 3110);
DISPLAY 0.680851 (-610 3110);
PAINT MONO (-610 3110);
FORCEPROP 0 LASTPIN (-600 3150) $PN J68
J 2
(-610 3160);
DISPLAY 0.680851 (-610 3160);
PAINT MONO (-610 3160);
FORCEPROP 0 LASTPIN (-600 3200) $PN M69
J 2
(-610 3210);
DISPLAY 0.680851 (-610 3210);
PAINT MONO (-610 3210);
FORCEPROP 0 LASTPIN (-600 3250) $PN N68
J 2
(-610 3260);
DISPLAY 0.680851 (-610 3260);
PAINT MONO (-610 3260);
FORCEPROP 0 LASTPIN (-600 3300) $PN J66
J 2
(-610 3310);
DISPLAY 0.680851 (-610 3310);
PAINT MONO (-610 3310);
FORCEPROP 0 LASTPIN (-600 3350) $PN K65
J 2
(-610 3360);
DISPLAY 0.680851 (-610 3360);
PAINT MONO (-610 3360);
FORCEPROP 0 LASTPIN (-600 3400) $PN N66
J 2
(-610 3410);
DISPLAY 0.680851 (-610 3410);
PAINT MONO (-610 3410);
FORCEPROP 0 LASTPIN (-600 3450) $PN M65
J 2
(-610 3460);
DISPLAY 0.680851 (-610 3460);
PAINT MONO (-610 3460);
FORCEPROP 0 LASTPIN (-600 3500) $PN B73
J 2
(-610 3510);
DISPLAY 0.680851 (-610 3510);
PAINT MONO (-610 3510);
FORCEPROP 0 LASTPIN (-600 3550) $PN E72
J 2
(-610 3560);
DISPLAY 0.680851 (-610 3560);
PAINT MONO (-610 3560);
FORCEPROP 0 LASTPIN (-600 3600) $PN D73
J 2
(-610 3610);
DISPLAY 0.680851 (-610 3610);
PAINT MONO (-610 3610);
FORCEPROP 0 LASTPIN (-600 3650) $PN F71
J 2
(-610 3660);
DISPLAY 0.680851 (-610 3660);
PAINT MONO (-610 3660);
FORCEPROP 0 LASTPIN (-600 3700) $PN B69
J 2
(-610 3710);
DISPLAY 0.680851 (-610 3710);
PAINT MONO (-610 3710);
FORCEPROP 0 LASTPIN (-600 3750) $PN C68
J 2
(-610 3760);
DISPLAY 0.680851 (-610 3760);
PAINT MONO (-610 3760);
FORCEPROP 0 LASTPIN (-600 3800) $PN F69
J 2
(-610 3810);
DISPLAY 0.680851 (-610 3810);
PAINT MONO (-610 3810);
FORCEPROP 0 LASTPIN (-600 3850) $PN E68
J 2
(-610 3860);
DISPLAY 0.680851 (-610 3860);
PAINT MONO (-610 3860);
FORCEPROP 0 LASTPIN (-600 3900) $PN C66
J 2
(-610 3910);
DISPLAY 0.680851 (-610 3910);
PAINT MONO (-610 3910);
FORCEPROP 0 LASTPIN (-600 3950) $PN B65
J 2
(-610 3960);
DISPLAY 0.680851 (-610 3960);
PAINT MONO (-610 3960);
FORCEPROP 0 LASTPIN (-600 4000) $PN E66
J 2
(-610 4010);
DISPLAY 0.680851 (-610 4010);
PAINT MONO (-610 4010);
FORCEPROP 0 LASTPIN (-600 4050) $PN F65
J 2
(-610 4060);
DISPLAY 0.680851 (-610 4060);
PAINT MONO (-610 4060);
FORCEPROP 0 LASTPIN (-600 4100) $PN B63
J 2
(-610 4110);
DISPLAY 0.680851 (-610 4110);
PAINT MONO (-610 4110);
FORCEPROP 0 LASTPIN (-600 4150) $PN C62
J 2
(-610 4160);
DISPLAY 0.680851 (-610 4160);
PAINT MONO (-610 4160);
FORCEPROP 0 LASTPIN (-600 4200) $PN F63
J 2
(-610 4210);
DISPLAY 0.680851 (-610 4210);
PAINT MONO (-610 4210);
FORCEPROP 0 LASTPIN (-600 4250) $PN E62
J 2
(-610 4260);
DISPLAY 0.680851 (-610 4260);
PAINT MONO (-610 4260);
FORCEPROP 0 LASTPIN (1850 3250) $PN B77
J 0
(1860 3260);
DISPLAY 0.680851 (1860 3260);
PAINT MONO (1860 3260);
FORCEPROP 0 LASTPIN (1850 3300) $PN H67
J 0
(1860 3310);
DISPLAY 0.680851 (1860 3310);
PAINT MONO (1860 3310);
FORCEPROP 0 LASTPIN (1850 3350) $PN B71
J 0
(1860 3360);
DISPLAY 0.680851 (1860 3360);
PAINT MONO (1860 3360);
FORCEPROP 0 LASTPIN (1850 3400) $PN A64
J 0
(1860 3410);
DISPLAY 0.680851 (1860 3410);
PAINT MONO (1860 3410);
FORCEPROP 0 LASTPIN (1850 3450) $PN A58
J 0
(1860 3460);
DISPLAY 0.680851 (1860 3460);
PAINT MONO (1860 3460);
FORCEPROP 0 LASTPIN (1850 3500) $PN H77
J 0
(1860 3510);
DISPLAY 0.680851 (1860 3510);
PAINT MONO (1860 3510);
FORCEPROP 0 LASTPIN (1850 3550) $PN P67
J 0
(1860 3560);
DISPLAY 0.680851 (1860 3560);
PAINT MONO (1860 3560);
FORCEPROP 0 LASTPIN (1850 3600) $PN G70
J 0
(1860 3610);
DISPLAY 0.680851 (1860 3610);
PAINT MONO (1860 3610);
FORCEPROP 0 LASTPIN (1850 3650) $PN G64
J 0
(1860 3660);
DISPLAY 0.680851 (1860 3660);
PAINT MONO (1860 3660);
FORCEPROP 0 LASTPIN (1850 3700) $PN G58
J 0
(1860 3710);
DISPLAY 0.680851 (1860 3710);
PAINT MONO (1860 3710);
FORCEPROP 0 LASTPIN (1850 3800) $PN D77
J 0
(1860 3810);
DISPLAY 0.680851 (1860 3810);
PAINT MONO (1860 3810);
FORCEPROP 0 LASTPIN (1850 3850) $PN K67
J 0
(1860 3860);
DISPLAY 0.680851 (1860 3860);
PAINT MONO (1860 3860);
FORCEPROP 0 LASTPIN (1850 3900) $PN C70
J 0
(1860 3910);
DISPLAY 0.680851 (1860 3910);
PAINT MONO (1860 3910);
FORCEPROP 0 LASTPIN (1850 3950) $PN C64
J 0
(1860 3960);
DISPLAY 0.680851 (1860 3960);
PAINT MONO (1860 3960);
FORCEPROP 0 LASTPIN (1850 4000) $PN C58
J 0
(1860 4010);
DISPLAY 0.680851 (1860 4010);
PAINT MONO (1860 4010);
FORCEPROP 0 LASTPIN (1850 4050) $PN F77
J 0
(1860 4060);
DISPLAY 0.680851 (1860 4060);
PAINT MONO (1860 4060);
FORCEPROP 0 LASTPIN (1850 4100) $PN M67
J 0
(1860 4110);
DISPLAY 0.680851 (1860 4110);
PAINT MONO (1860 4110);
FORCEPROP 0 LASTPIN (1850 4150) $PN E70
J 0
(1860 4160);
DISPLAY 0.680851 (1860 4160);
PAINT MONO (1860 4160);
FORCEPROP 0 LASTPIN (1850 4200) $PN E64
J 0
(1860 4210);
DISPLAY 0.680851 (1860 4210);
PAINT MONO (1860 4210);
FORCEPROP 0 LASTPIN (1850 4250) $PN E58
J 0
(1860 4260);
DISPLAY 0.680851 (1860 4260);
PAINT MONO (1860 4260);
FORCEPROP 0 LASTPIN (-600 2300) $PN C60
J 2
(-610 2310);
DISPLAY 0.680851 (-610 2310);
PAINT MONO (-610 2310);
FORCEPROP 0 LASTPIN (-600 2350) $PN B59
J 2
(-610 2360);
DISPLAY 0.680851 (-610 2360);
PAINT MONO (-610 2360);
FORCEPROP 0 LASTPIN (-600 2400) $PN E60
J 2
(-610 2410);
DISPLAY 0.680851 (-610 2410);
PAINT MONO (-610 2410);
FORCEPROP 0 LASTPIN (-600 2450) $PN F59
J 2
(-610 2460);
DISPLAY 0.680851 (-610 2460);
PAINT MONO (-610 2460);
FORCEPROP 0 LASTPIN (-600 2500) $PN B57
J 2
(-610 2510);
DISPLAY 0.680851 (-610 2510);
PAINT MONO (-610 2510);
FORCEPROP 0 LASTPIN (-600 2550) $PN C56
J 2
(-610 2560);
DISPLAY 0.680851 (-610 2560);
PAINT MONO (-610 2560);
FORCEPROP 0 LASTPIN (-600 2600) $PN F57
J 2
(-610 2610);
DISPLAY 0.680851 (-610 2610);
PAINT MONO (-610 2610);
FORCEPROP 0 LASTPIN (-600 2650) $PN E56
J 2
(-610 2660);
DISPLAY 0.680851 (-610 2660);
PAINT MONO (-610 2660);
FORCEPROP 0 LASTPIN (1850 1600) $PN E48
J 0
(1860 1610);
DISPLAY 0.680851 (1860 1610);
PAINT MONO (1860 1610);
FORCEPROP 0 LASTPIN (1850 1150) $PN E43
J 0
(1860 1160);
DISPLAY 0.680851 (1860 1160);
PAINT MONO (1860 1160);
FORCEPROP 0 LASTPIN (1850 1200) $PN F44
J 0
(1860 1210);
DISPLAY 0.680851 (1860 1210);
PAINT MONO (1860 1210);
FORCEPROP 0 LASTPIN (1850 1250) $PN C41
J 0
(1860 1260);
DISPLAY 0.680851 (1860 1260);
PAINT MONO (1860 1260);
FORCEPROP 0 LASTPIN (1850 1300) $PN E41
J 0
(1860 1310);
DISPLAY 0.680851 (1860 1310);
PAINT MONO (1860 1310);
FORCEPROP 0 LASTPIN (1850 1350) $PN B40
J 0
(1860 1360);
DISPLAY 0.680851 (1860 1360);
PAINT MONO (1860 1360);
FORCEPROP 0 LASTPIN (1850 1400) $PN F40
J 0
(1860 1410);
DISPLAY 0.680851 (1860 1410);
PAINT MONO (1860 1410);
FORCEPROP 0 LASTPIN (1850 1450) $PN A39
J 0
(1860 1460);
DISPLAY 0.680851 (1860 1460);
PAINT MONO (1860 1460);
FORCEPROP 0 LASTPIN (-600 700) $PN K32
J 2
(-610 710);
DISPLAY 0.680851 (-610 710);
PAINT MONO (-610 710);
FORCEPROP 0 LASTPIN (-600 750) $PN J31
J 2
(-610 760);
DISPLAY 0.680851 (-610 760);
PAINT MONO (-610 760);
FORCEPROP 0 LASTPIN (-600 800) $PN M32
J 2
(-610 810);
DISPLAY 0.680851 (-610 810);
PAINT MONO (-610 810);
FORCEPROP 0 LASTPIN (-600 850) $PN N31
J 2
(-610 860);
DISPLAY 0.680851 (-610 860);
PAINT MONO (-610 860);
FORCEPROP 0 LASTPIN (-600 900) $PN J29
J 2
(-610 910);
DISPLAY 0.680851 (-610 910);
PAINT MONO (-610 910);
FORCEPROP 0 LASTPIN (-600 950) $PN K28
J 2
(-610 960);
DISPLAY 0.680851 (-610 960);
PAINT MONO (-610 960);
FORCEPROP 0 LASTPIN (-600 1000) $PN N29
J 2
(-610 1010);
DISPLAY 0.680851 (-610 1010);
PAINT MONO (-610 1010);
FORCEPROP 0 LASTPIN (-600 1050) $PN M28
J 2
(-610 1060);
DISPLAY 0.680851 (-610 1060);
PAINT MONO (-610 1060);
FORCEPROP 0 LASTPIN (-600 1100) $PN C29
J 2
(-610 1110);
DISPLAY 0.680851 (-610 1110);
PAINT MONO (-610 1110);
FORCEPROP 0 LASTPIN (-600 1150) $PN B28
J 2
(-610 1160);
DISPLAY 0.680851 (-610 1160);
PAINT MONO (-610 1160);
FORCEPROP 0 LASTPIN (-600 1200) $PN E29
J 2
(-610 1210);
DISPLAY 0.680851 (-610 1210);
PAINT MONO (-610 1210);
FORCEPROP 0 LASTPIN (-600 1250) $PN F28
J 2
(-610 1260);
DISPLAY 0.680851 (-610 1260);
PAINT MONO (-610 1260);
FORCEPROP 0 LASTPIN (-600 1300) $PN B26
J 2
(-610 1310);
DISPLAY 0.680851 (-610 1310);
PAINT MONO (-610 1310);
FORCEPROP 0 LASTPIN (-600 1350) $PN C25
J 2
(-610 1360);
DISPLAY 0.680851 (-610 1360);
PAINT MONO (-610 1360);
FORCEPROP 0 LASTPIN (-600 1400) $PN F26
J 2
(-610 1410);
DISPLAY 0.680851 (-610 1410);
PAINT MONO (-610 1410);
FORCEPROP 0 LASTPIN (-600 1450) $PN E25
J 2
(-610 1460);
DISPLAY 0.680851 (-610 1460);
PAINT MONO (-610 1460);
FORCEPROP 0 LASTPIN (-600 1500) $PN C23
J 2
(-610 1510);
DISPLAY 0.680851 (-610 1510);
PAINT MONO (-610 1510);
FORCEPROP 0 LASTPIN (-600 1550) $PN B22
J 2
(-610 1560);
DISPLAY 0.680851 (-610 1560);
PAINT MONO (-610 1560);
FORCEPROP 0 LASTPIN (-600 1600) $PN E23
J 2
(-610 1610);
DISPLAY 0.680851 (-610 1610);
PAINT MONO (-610 1610);
FORCEPROP 0 LASTPIN (-600 1650) $PN F22
J 2
(-610 1660);
DISPLAY 0.680851 (-610 1660);
PAINT MONO (-610 1660);
FORCEPROP 0 LASTPIN (-600 1700) $PN B20
J 2
(-610 1710);
DISPLAY 0.680851 (-610 1710);
PAINT MONO (-610 1710);
FORCEPROP 0 LASTPIN (-600 1750) $PN C19
J 2
(-610 1760);
DISPLAY 0.680851 (-610 1760);
PAINT MONO (-610 1760);
FORCEPROP 0 LASTPIN (-600 1800) $PN F20
J 2
(-610 1810);
DISPLAY 0.680851 (-610 1810);
PAINT MONO (-610 1810);
FORCEPROP 0 LASTPIN (-600 1850) $PN E19
J 2
(-610 1860);
DISPLAY 0.680851 (-610 1860);
PAINT MONO (-610 1860);
FORCEPROP 0 LASTPIN (-600 1900) $PN C11
J 2
(-610 1910);
DISPLAY 0.680851 (-610 1910);
PAINT MONO (-610 1910);
FORCEPROP 0 LASTPIN (-600 1950) $PN B10
J 2
(-610 1960);
DISPLAY 0.680851 (-610 1960);
PAINT MONO (-610 1960);
FORCEPROP 0 LASTPIN (-600 2150) $PN C7
J 2
(-610 2160);
DISPLAY 0.680851 (-610 2160);
PAINT MONO (-610 2160);
FORCEPROP 0 LASTPIN (-600 2200) $PN F8
J 2
(-610 2210);
DISPLAY 0.680851 (-610 2210);
PAINT MONO (-610 2210);
FORCEPROP 0 LASTPIN (-600 2250) $PN E7
J 2
(-610 2260);
DISPLAY 0.680851 (-610 2260);
PAINT MONO (-610 2260);
FORCEPROP 0 LASTPIN (1850 2100) $PN H30
J 0
(1860 2110);
DISPLAY 0.680851 (1860 2110);
PAINT MONO (1860 2110);
FORCEPROP 0 LASTPIN (1850 2150) $PN A27
J 0
(1860 2160);
DISPLAY 0.680851 (1860 2160);
PAINT MONO (1860 2160);
FORCEPROP 0 LASTPIN (1850 2200) $PN A21
J 0
(1860 2210);
DISPLAY 0.680851 (1860 2210);
PAINT MONO (1860 2210);
FORCEPROP 0 LASTPIN (1850 2250) $PN A9
J 0
(1860 2260);
DISPLAY 0.680851 (1860 2260);
PAINT MONO (1860 2260);
FORCEPROP 0 LASTPIN (1850 2300) $PN G33
J 0
(1860 2310);
DISPLAY 0.680851 (1860 2310);
PAINT MONO (1860 2310);
FORCEPROP 0 LASTPIN (1850 2350) $PN M30
J 0
(1860 2360);
DISPLAY 0.680851 (1860 2360);
PAINT MONO (1860 2360);
FORCEPROP 0 LASTPIN (1850 2400) $PN G27
J 0
(1860 2410);
DISPLAY 0.680851 (1860 2410);
PAINT MONO (1860 2410);
FORCEPROP 0 LASTPIN (1850 2450) $PN G21
J 0
(1860 2460);
DISPLAY 0.680851 (1860 2460);
PAINT MONO (1860 2460);
FORCEPROP 0 LASTPIN (1850 2500) $PN G9
J 0
(1860 2510);
DISPLAY 0.680851 (1860 2510);
PAINT MONO (1860 2510);
FORCEPROP 0 LASTPIN (1850 2550) $PN A33
J 0
(1860 2560);
DISPLAY 0.680851 (1860 2560);
PAINT MONO (1860 2560);
FORCEPROP 0 LASTPIN (1850 2650) $PN K30
J 0
(1860 2660);
DISPLAY 0.680851 (1860 2660);
PAINT MONO (1860 2660);
FORCEPROP 0 LASTPIN (1850 2700) $PN C27
J 0
(1860 2710);
DISPLAY 0.680851 (1860 2710);
PAINT MONO (1860 2710);
FORCEPROP 0 LASTPIN (1850 2750) $PN C21
J 0
(1860 2760);
DISPLAY 0.680851 (1860 2760);
PAINT MONO (1860 2760);
FORCEPROP 0 LASTPIN (1850 2800) $PN C9
J 0
(1860 2810);
DISPLAY 0.680851 (1860 2810);
PAINT MONO (1860 2810);
FORCEPROP 0 LASTPIN (1850 2850) $PN E33
J 0
(1860 2860);
DISPLAY 0.680851 (1860 2860);
PAINT MONO (1860 2860);
FORCEPROP 0 LASTPIN (1850 2900) $PN P30
J 0
(1860 2910);
DISPLAY 0.680851 (1860 2910);
PAINT MONO (1860 2910);
FORCEPROP 0 LASTPIN (1850 2950) $PN E27
J 0
(1860 2960);
DISPLAY 0.680851 (1860 2960);
PAINT MONO (1860 2960);
FORCEPROP 0 LASTPIN (1850 3000) $PN E21
J 0
(1860 3010);
DISPLAY 0.680851 (1860 3010);
PAINT MONO (1860 3010);
FORCEPROP 0 LASTPIN (1850 3050) $PN E9
J 0
(1860 3060);
DISPLAY 0.680851 (1860 3060);
PAINT MONO (1860 3060);
FORCEPROP 0 LASTPIN (1850 3100) $PN C33
J 0
(1860 3110);
DISPLAY 0.680851 (1860 3110);
PAINT MONO (1860 3110);
FORCEPROP 0 LASTPIN (-600 300) $PN B32
J 2
(-610 310);
DISPLAY 0.680851 (-610 310);
PAINT MONO (-610 310);
FORCEPROP 0 LASTPIN (-600 350) $PN C31
J 2
(-610 360);
DISPLAY 0.680851 (-610 360);
PAINT MONO (-610 360);
FORCEPROP 0 LASTPIN (-600 400) $PN F32
J 2
(-610 410);
DISPLAY 0.680851 (-610 410);
PAINT MONO (-610 410);
FORCEPROP 0 LASTPIN (-600 450) $PN E31
J 2
(-610 460);
DISPLAY 0.680851 (-610 460);
PAINT MONO (-610 460);
FORCEPROP 0 LASTPIN (-600 500) $PN C35
J 2
(-610 510);
DISPLAY 0.680851 (-610 510);
PAINT MONO (-610 510);
FORCEPROP 0 LASTPIN (-600 550) $PN B34
J 2
(-610 560);
DISPLAY 0.680851 (-610 560);
PAINT MONO (-610 560);
FORCEPROP 0 LASTPIN (-600 600) $PN E35
J 2
(-610 610);
DISPLAY 0.680851 (-610 610);
PAINT MONO (-610 610);
FORCEPROP 0 LASTPIN (-600 650) $PN F34
J 2
(-610 660);
DISPLAY 0.680851 (-610 660);
PAINT MONO (-610 660);
FORCEPROP 0 LASTPIN (1850 1100) $PN G39
J 0
(1860 1110);
DISPLAY 0.680851 (1860 1110);
PAINT MONO (1860 1110);
FORCEPROP 0 LASTPIN (1850 800) $PN C54
J 0
(1860 810);
DISPLAY 0.680851 (1860 810);
PAINT MONO (1860 810);
FORCEPROP 0 LASTPIN (1850 850) $PN B53
J 0
(1860 860);
DISPLAY 0.680851 (1860 860);
PAINT MONO (1860 860);
FORCEPROP 0 LASTPIN (1850 900) $PN E54
J 0
(1860 910);
DISPLAY 0.680851 (1860 910);
PAINT MONO (1860 910);
FORCEPROP 0 LASTPIN (1850 950) $PN F53
J 0
(1860 960);
DISPLAY 0.680851 (1860 960);
PAINT MONO (1860 960);
FORCEPROP 0 LASTPIN (1850 500) $PN B38
J 0
(1860 510);
DISPLAY 0.680851 (1860 510);
PAINT MONO (1860 510);
FORCEPROP 0 LASTPIN (1850 550) $PN C37
J 0
(1860 560);
DISPLAY 0.680851 (1860 560);
PAINT MONO (1860 560);
FORCEPROP 0 LASTPIN (1850 600) $PN F38
J 0
(1860 610);
DISPLAY 0.680851 (1860 610);
PAINT MONO (1860 610);
FORCEPROP 0 LASTPIN (1850 650) $PN E37
J 0
(1860 660);
DISPLAY 0.680851 (1860 660);
PAINT MONO (1860 660);
FORCEPROP 0 LASTPIN (-600 2000) $PN E11
J 2
(-610 2010);
DISPLAY 0.680851 (-610 2010);
PAINT MONO (-610 2010);
FORCEPROP 0 LASTPIN (-600 2050) $PN F10
J 2
(-610 2060);
DISPLAY 0.680851 (-610 2060);
PAINT MONO (-610 2060);
FORCEPROP 0 LASTPIN (-600 2100) $PN B8
J 2
(-610 2110);
DISPLAY 0.680851 (-610 2110);
PAINT MONO (-610 2110);
FORCEPROP 2 LAST CDS_LIB pure_quanta
J 0
(625 2150);
DISPLAY INVISIBLE (625 2150);
FORCEPROP 1 LAST NEEDS_NO_SIZE TRUE
J 0
(625 2150);
DISPLAY 0.723404 (625 2150);
PAINT GREEN (625 2150);
DISPLAY INVISIBLE (625 2150);
FORCEPROP 1 LAST CDS_LMAN_SYM_OUTLINE -1100,2250,1050,-2250
J 0
(625 2150);
DISPLAY 0.468085 (625 2150);
PAINT GREEN (625 2150);
DISPLAY INVISIBLE (625 2150);
FORCEPROP 2 LAST CDS_LOCATION U1
J 0
(-475 4725);
DISPLAY 1.021277 (-475 4725);
DISPLAY INVISIBLE (-475 4725);
FORCEPROP 0 LAST $SEC 8
J 0
(-475 4725);
DISPLAY 0.680851 (-475 4725);
PAINT MONO (-475 4725);
DISPLAY INVISIBLE (-475 4725);
FORCEPROP 2 LAST CDS_SEC 8
J 0
(-475 4725);
DISPLAY 1.021277 (-475 4725);
DISPLAY INVISIBLE (-475 4725);
FORCEPROP 1 LAST PATH I2
J 0
(625 2150);
DISPLAY 0.723404 (625 2150);
PAINT GREEN (625 2150);
DISPLAY INVISIBLE (625 2150);
FORCEADD TAP..1
R 2
(-1100 850);
FORCEPROP 3 LASTPIN (-1050 850) SIG_NAME M_A_CPU1_SB_DQ<3>
J 0
(-1040 860);
DISPLAY 0.659574 (-1040 860);
PAINT MONO (-1040 860);
DISPLAY INVISIBLE (-1040 860);
FORCEPROP 1 LASTPIN (-1050 850) BN 3
J 2
(-1038 858);
DISPLAY 0.680851 (-1038 858);
PAINT GREEN (-1038 858);
FORCEPROP 2 LAST CDS_LIB standard
J 0
(-1100 850);
DISPLAY INVISIBLE (-1100 850);
FORCEPROP 1 LAST BODY_TYPE PLUMBING
J 2
(-1100 900);
DISPLAY 0.872340 (-1100 900);
PAINT GREEN (-1100 900);
DISPLAY INVISIBLE (-1100 900);
FORCEPROP 1 LAST HDL_TAP TRUE
J 2
(-1425 725);
DISPLAY 0.872340 (-1425 725);
DISPLAY INVISIBLE (-1425 725);
FORCEPROP 1 LAST PATH I20
J 2
(-1098 850);
DISPLAY 0.872340 (-1098 850);
PAINT GREEN (-1098 850);
DISPLAY INVISIBLE (-1098 850);
FORCEADD TAP..1
R 2
(-1100 900);
FORCEPROP 3 LASTPIN (-1050 900) SIG_NAME M_A_CPU1_SB_DQ<4>
J 0
(-1040 910);
DISPLAY 0.659574 (-1040 910);
PAINT MONO (-1040 910);
DISPLAY INVISIBLE (-1040 910);
FORCEPROP 1 LASTPIN (-1050 900) BN 4
J 2
(-1038 908);
DISPLAY 0.680851 (-1038 908);
PAINT GREEN (-1038 908);
FORCEPROP 2 LAST CDS_LIB standard
J 0
(-1100 900);
DISPLAY INVISIBLE (-1100 900);
FORCEPROP 1 LAST BODY_TYPE PLUMBING
J 2
(-1100 950);
DISPLAY 0.872340 (-1100 950);
PAINT GREEN (-1100 950);
DISPLAY INVISIBLE (-1100 950);
FORCEPROP 1 LAST HDL_TAP TRUE
J 2
(-1425 775);
DISPLAY 0.872340 (-1425 775);
DISPLAY INVISIBLE (-1425 775);
FORCEPROP 1 LAST PATH I21
J 2
(-1098 900);
DISPLAY 0.872340 (-1098 900);
PAINT GREEN (-1098 900);
DISPLAY INVISIBLE (-1098 900);
FORCEADD TAP..1
R 2
(-1100 1000);
FORCEPROP 3 LASTPIN (-1050 1000) SIG_NAME M_A_CPU1_SB_DQ<6>
J 0
(-1040 1010);
DISPLAY 0.659574 (-1040 1010);
PAINT MONO (-1040 1010);
DISPLAY INVISIBLE (-1040 1010);
FORCEPROP 1 LASTPIN (-1050 1000) BN 6
J 2
(-1038 1008);
DISPLAY 0.680851 (-1038 1008);
PAINT GREEN (-1038 1008);
FORCEPROP 2 LAST CDS_LIB standard
J 0
(-1100 1000);
DISPLAY INVISIBLE (-1100 1000);
FORCEPROP 1 LAST BODY_TYPE PLUMBING
J 2
(-1100 1050);
DISPLAY 0.872340 (-1100 1050);
PAINT GREEN (-1100 1050);
DISPLAY INVISIBLE (-1100 1050);
FORCEPROP 1 LAST HDL_TAP TRUE
J 2
(-1425 875);
DISPLAY 0.872340 (-1425 875);
DISPLAY INVISIBLE (-1425 875);
FORCEPROP 1 LAST PATH I22
J 2
(-1098 1000);
DISPLAY 0.872340 (-1098 1000);
PAINT GREEN (-1098 1000);
DISPLAY INVISIBLE (-1098 1000);
FORCEADD TAP..1
R 2
(-1100 950);
FORCEPROP 3 LASTPIN (-1050 950) SIG_NAME M_A_CPU1_SB_DQ<5>
J 0
(-1040 960);
DISPLAY 0.659574 (-1040 960);
PAINT MONO (-1040 960);
DISPLAY INVISIBLE (-1040 960);
FORCEPROP 1 LASTPIN (-1050 950) BN 5
J 2
(-1038 958);
DISPLAY 0.680851 (-1038 958);
PAINT GREEN (-1038 958);
FORCEPROP 2 LAST CDS_LIB standard
J 0
(-1100 950);
DISPLAY INVISIBLE (-1100 950);
FORCEPROP 1 LAST BODY_TYPE PLUMBING
J 2
(-1100 1000);
DISPLAY 0.872340 (-1100 1000);
PAINT GREEN (-1100 1000);
DISPLAY INVISIBLE (-1100 1000);
FORCEPROP 1 LAST HDL_TAP TRUE
J 2
(-1425 825);
DISPLAY 0.872340 (-1425 825);
DISPLAY INVISIBLE (-1425 825);
FORCEPROP 1 LAST PATH I23
J 2
(-1098 950);
DISPLAY 0.872340 (-1098 950);
PAINT GREEN (-1098 950);
DISPLAY INVISIBLE (-1098 950);
FORCEADD TAP..1
R 2
(-1100 1050);
FORCEPROP 3 LASTPIN (-1050 1050) SIG_NAME M_A_CPU1_SB_DQ<7>
J 0
(-1040 1060);
DISPLAY 0.659574 (-1040 1060);
PAINT MONO (-1040 1060);
DISPLAY INVISIBLE (-1040 1060);
FORCEPROP 1 LASTPIN (-1050 1050) BN 7
J 2
(-1038 1058);
DISPLAY 0.680851 (-1038 1058);
PAINT GREEN (-1038 1058);
FORCEPROP 2 LAST CDS_LIB standard
J 0
(-1100 1050);
DISPLAY INVISIBLE (-1100 1050);
FORCEPROP 1 LAST BODY_TYPE PLUMBING
J 2
(-1100 1100);
DISPLAY 0.872340 (-1100 1100);
PAINT GREEN (-1100 1100);
DISPLAY INVISIBLE (-1100 1100);
FORCEPROP 1 LAST HDL_TAP TRUE
J 2
(-1425 925);
DISPLAY 0.872340 (-1425 925);
DISPLAY INVISIBLE (-1425 925);
FORCEPROP 1 LAST PATH I24
J 2
(-1098 1050);
DISPLAY 0.872340 (-1098 1050);
PAINT GREEN (-1098 1050);
DISPLAY INVISIBLE (-1098 1050);
FORCEADD TAP..1
R 2
(-1100 1150);
FORCEPROP 3 LASTPIN (-1050 1150) SIG_NAME M_A_CPU1_SB_DQ<9>
J 0
(-1040 1160);
DISPLAY 0.659574 (-1040 1160);
PAINT MONO (-1040 1160);
DISPLAY INVISIBLE (-1040 1160);
FORCEPROP 1 LASTPIN (-1050 1150) BN 9
J 2
(-1038 1158);
DISPLAY 0.680851 (-1038 1158);
PAINT GREEN (-1038 1158);
FORCEPROP 2 LAST CDS_LIB standard
J 0
(-1100 1150);
DISPLAY INVISIBLE (-1100 1150);
FORCEPROP 1 LAST BODY_TYPE PLUMBING
J 2
(-1100 1200);
DISPLAY 0.872340 (-1100 1200);
PAINT GREEN (-1100 1200);
DISPLAY INVISIBLE (-1100 1200);
FORCEPROP 1 LAST HDL_TAP TRUE
J 2
(-1425 1025);
DISPLAY 0.872340 (-1425 1025);
DISPLAY INVISIBLE (-1425 1025);
FORCEPROP 1 LAST PATH I25
J 2
(-1098 1150);
DISPLAY 0.872340 (-1098 1150);
PAINT GREEN (-1098 1150);
DISPLAY INVISIBLE (-1098 1150);
FORCEADD TAP..1
R 2
(-1100 1100);
FORCEPROP 3 LASTPIN (-1050 1100) SIG_NAME M_A_CPU1_SB_DQ<8>
J 0
(-1040 1110);
DISPLAY 0.659574 (-1040 1110);
PAINT MONO (-1040 1110);
DISPLAY INVISIBLE (-1040 1110);
FORCEPROP 1 LASTPIN (-1050 1100) BN 8
J 2
(-1038 1108);
DISPLAY 0.680851 (-1038 1108);
PAINT GREEN (-1038 1108);
FORCEPROP 2 LAST CDS_LIB standard
J 0
(-1100 1100);
DISPLAY INVISIBLE (-1100 1100);
FORCEPROP 1 LAST BODY_TYPE PLUMBING
J 2
(-1100 1150);
DISPLAY 0.872340 (-1100 1150);
PAINT GREEN (-1100 1150);
DISPLAY INVISIBLE (-1100 1150);
FORCEPROP 1 LAST HDL_TAP TRUE
J 2
(-1425 975);
DISPLAY 0.872340 (-1425 975);
DISPLAY INVISIBLE (-1425 975);
FORCEPROP 1 LAST PATH I26
J 2
(-1098 1100);
DISPLAY 0.872340 (-1098 1100);
PAINT GREEN (-1098 1100);
DISPLAY INVISIBLE (-1098 1100);
FORCEADD TAP..1
R 2
(-1100 1300);
FORCEPROP 3 LASTPIN (-1050 1300) SIG_NAME M_A_CPU1_SB_DQ<12>
J 0
(-1040 1310);
DISPLAY 0.659574 (-1040 1310);
PAINT MONO (-1040 1310);
DISPLAY INVISIBLE (-1040 1310);
FORCEPROP 1 LASTPIN (-1050 1300) BN 12
J 2
(-1038 1308);
DISPLAY 0.680851 (-1038 1308);
PAINT GREEN (-1038 1308);
FORCEPROP 2 LAST CDS_LIB standard
J 0
(-1100 1300);
DISPLAY INVISIBLE (-1100 1300);
FORCEPROP 1 LAST BODY_TYPE PLUMBING
J 2
(-1100 1350);
DISPLAY 0.872340 (-1100 1350);
PAINT GREEN (-1100 1350);
DISPLAY INVISIBLE (-1100 1350);
FORCEPROP 1 LAST HDL_TAP TRUE
J 2
(-1425 1175);
DISPLAY 0.872340 (-1425 1175);
DISPLAY INVISIBLE (-1425 1175);
FORCEPROP 1 LAST PATH I27
J 2
(-1098 1300);
DISPLAY 0.872340 (-1098 1300);
PAINT GREEN (-1098 1300);
DISPLAY INVISIBLE (-1098 1300);
FORCEADD TAP..1
R 2
(-1100 1250);
FORCEPROP 3 LASTPIN (-1050 1250) SIG_NAME M_A_CPU1_SB_DQ<11>
J 0
(-1040 1260);
DISPLAY 0.659574 (-1040 1260);
PAINT MONO (-1040 1260);
DISPLAY INVISIBLE (-1040 1260);
FORCEPROP 1 LASTPIN (-1050 1250) BN 11
J 2
(-1038 1258);
DISPLAY 0.680851 (-1038 1258);
PAINT GREEN (-1038 1258);
FORCEPROP 2 LAST CDS_LIB standard
J 0
(-1100 1250);
DISPLAY INVISIBLE (-1100 1250);
FORCEPROP 1 LAST BODY_TYPE PLUMBING
J 2
(-1100 1300);
DISPLAY 0.872340 (-1100 1300);
PAINT GREEN (-1100 1300);
DISPLAY INVISIBLE (-1100 1300);
FORCEPROP 1 LAST HDL_TAP TRUE
J 2
(-1425 1125);
DISPLAY 0.872340 (-1425 1125);
DISPLAY INVISIBLE (-1425 1125);
FORCEPROP 1 LAST PATH I28
J 2
(-1098 1250);
DISPLAY 0.872340 (-1098 1250);
PAINT GREEN (-1098 1250);
DISPLAY INVISIBLE (-1098 1250);
FORCEADD TAP..1
R 2
(-1100 1200);
FORCEPROP 3 LASTPIN (-1050 1200) SIG_NAME M_A_CPU1_SB_DQ<10>
J 0
(-1040 1210);
DISPLAY 0.659574 (-1040 1210);
PAINT MONO (-1040 1210);
DISPLAY INVISIBLE (-1040 1210);
FORCEPROP 1 LASTPIN (-1050 1200) BN 10
J 2
(-1038 1208);
DISPLAY 0.680851 (-1038 1208);
PAINT GREEN (-1038 1208);
FORCEPROP 2 LAST CDS_LIB standard
J 0
(-1100 1200);
DISPLAY INVISIBLE (-1100 1200);
FORCEPROP 1 LAST BODY_TYPE PLUMBING
J 2
(-1100 1250);
DISPLAY 0.872340 (-1100 1250);
PAINT GREEN (-1100 1250);
DISPLAY INVISIBLE (-1100 1250);
FORCEPROP 1 LAST HDL_TAP TRUE
J 2
(-1425 1075);
DISPLAY 0.872340 (-1425 1075);
DISPLAY INVISIBLE (-1425 1075);
FORCEPROP 1 LAST PATH I29
J 2
(-1098 1200);
DISPLAY 0.872340 (-1098 1200);
PAINT GREEN (-1098 1200);
DISPLAY INVISIBLE (-1098 1200);
FORCEADD OFFPAGE..2
R 2
(-2125 225);
FORCEPROP 2 LAST $XR1 99 
J 0
(-2469 225);
DISPLAY 0.638298 (-2469 225);
PAINT MONO (-2469 225);
FORCEPROP 2 LAST $XR0 98 
J 0
(-2379 225);
DISPLAY 0.638298 (-2379 225);
PAINT MONO (-2379 225);
FORCEPROP 2 LAST CDS_LIB standard
J 0
(-2125 225);
PAINT MONO (-2125 225);
DISPLAY INVISIBLE (-2125 225);
FORCEPROP 1 LAST OFFPAGE TRUE
J 2
(-2450 100);
DISPLAY 0.872340 (-2450 100);
DISPLAY INVISIBLE (-2450 100);
FORCEPROP 1 LAST COMMENT_BODY TRUE
J 2
(-2080 130);
DISPLAY 0.872340 (-2080 130);
PAINT GREEN (-2080 130);
DISPLAY INVISIBLE (-2080 130);
FORCEPROP 2 LAST PATH I3
J 0
(-2075 300);
DISPLAY 1.021277 (-2075 300);
DISPLAY INVISIBLE (-2075 300);
FORCEADD TAP..1
R 2
(-1100 1350);
FORCEPROP 3 LASTPIN (-1050 1350) SIG_NAME M_A_CPU1_SB_DQ<13>
J 0
(-1040 1360);
DISPLAY 0.659574 (-1040 1360);
PAINT MONO (-1040 1360);
DISPLAY INVISIBLE (-1040 1360);
FORCEPROP 1 LASTPIN (-1050 1350) BN 13
J 2
(-1038 1358);
DISPLAY 0.680851 (-1038 1358);
PAINT GREEN (-1038 1358);
FORCEPROP 2 LAST CDS_LIB standard
J 0
(-1100 1350);
DISPLAY INVISIBLE (-1100 1350);
FORCEPROP 1 LAST BODY_TYPE PLUMBING
J 2
(-1100 1400);
DISPLAY 0.872340 (-1100 1400);
PAINT GREEN (-1100 1400);
DISPLAY INVISIBLE (-1100 1400);
FORCEPROP 1 LAST HDL_TAP TRUE
J 2
(-1425 1225);
DISPLAY 0.872340 (-1425 1225);
DISPLAY INVISIBLE (-1425 1225);
FORCEPROP 1 LAST PATH I30
J 2
(-1098 1350);
DISPLAY 0.872340 (-1098 1350);
PAINT GREEN (-1098 1350);
DISPLAY INVISIBLE (-1098 1350);
FORCEADD TAP..1
R 2
(-1100 1400);
FORCEPROP 3 LASTPIN (-1050 1400) SIG_NAME M_A_CPU1_SB_DQ<14>
J 0
(-1040 1410);
DISPLAY 0.659574 (-1040 1410);
PAINT MONO (-1040 1410);
DISPLAY INVISIBLE (-1040 1410);
FORCEPROP 1 LASTPIN (-1050 1400) BN 14
J 2
(-1038 1408);
DISPLAY 0.680851 (-1038 1408);
PAINT GREEN (-1038 1408);
FORCEPROP 2 LAST CDS_LIB standard
J 0
(-1100 1400);
DISPLAY INVISIBLE (-1100 1400);
FORCEPROP 1 LAST BODY_TYPE PLUMBING
J 2
(-1100 1450);
DISPLAY 0.872340 (-1100 1450);
PAINT GREEN (-1100 1450);
DISPLAY INVISIBLE (-1100 1450);
FORCEPROP 1 LAST HDL_TAP TRUE
J 2
(-1425 1275);
DISPLAY 0.872340 (-1425 1275);
DISPLAY INVISIBLE (-1425 1275);
FORCEPROP 1 LAST PATH I31
J 2
(-1098 1400);
DISPLAY 0.872340 (-1098 1400);
PAINT GREEN (-1098 1400);
DISPLAY INVISIBLE (-1098 1400);
FORCEADD TAP..1
R 2
(-1100 1500);
FORCEPROP 3 LASTPIN (-1050 1500) SIG_NAME M_A_CPU1_SB_DQ<16>
J 0
(-1040 1510);
DISPLAY 0.659574 (-1040 1510);
PAINT MONO (-1040 1510);
DISPLAY INVISIBLE (-1040 1510);
FORCEPROP 1 LASTPIN (-1050 1500) BN 16
J 2
(-1038 1508);
DISPLAY 0.680851 (-1038 1508);
PAINT GREEN (-1038 1508);
FORCEPROP 2 LAST CDS_LIB standard
J 0
(-1100 1500);
DISPLAY INVISIBLE (-1100 1500);
FORCEPROP 1 LAST BODY_TYPE PLUMBING
J 2
(-1100 1550);
DISPLAY 0.872340 (-1100 1550);
PAINT GREEN (-1100 1550);
DISPLAY INVISIBLE (-1100 1550);
FORCEPROP 1 LAST HDL_TAP TRUE
J 2
(-1425 1375);
DISPLAY 0.872340 (-1425 1375);
DISPLAY INVISIBLE (-1425 1375);
FORCEPROP 1 LAST PATH I32
J 2
(-1098 1500);
DISPLAY 0.872340 (-1098 1500);
PAINT GREEN (-1098 1500);
DISPLAY INVISIBLE (-1098 1500);
FORCEADD TAP..1
R 2
(-1100 1550);
FORCEPROP 3 LASTPIN (-1050 1550) SIG_NAME M_A_CPU1_SB_DQ<17>
J 0
(-1040 1560);
DISPLAY 0.659574 (-1040 1560);
PAINT MONO (-1040 1560);
DISPLAY INVISIBLE (-1040 1560);
FORCEPROP 1 LASTPIN (-1050 1550) BN 17
J 2
(-1038 1558);
DISPLAY 0.680851 (-1038 1558);
PAINT GREEN (-1038 1558);
FORCEPROP 2 LAST CDS_LIB standard
J 0
(-1100 1550);
DISPLAY INVISIBLE (-1100 1550);
FORCEPROP 1 LAST BODY_TYPE PLUMBING
J 2
(-1100 1600);
DISPLAY 0.872340 (-1100 1600);
PAINT GREEN (-1100 1600);
DISPLAY INVISIBLE (-1100 1600);
FORCEPROP 1 LAST HDL_TAP TRUE
J 2
(-1425 1425);
DISPLAY 0.872340 (-1425 1425);
DISPLAY INVISIBLE (-1425 1425);
FORCEPROP 1 LAST PATH I33
J 2
(-1098 1550);
DISPLAY 0.872340 (-1098 1550);
PAINT GREEN (-1098 1550);
DISPLAY INVISIBLE (-1098 1550);
FORCEADD TAP..1
R 2
(-1100 1450);
FORCEPROP 3 LASTPIN (-1050 1450) SIG_NAME M_A_CPU1_SB_DQ<15>
J 0
(-1040 1460);
DISPLAY 0.659574 (-1040 1460);
PAINT MONO (-1040 1460);
DISPLAY INVISIBLE (-1040 1460);
FORCEPROP 1 LASTPIN (-1050 1450) BN 15
J 2
(-1038 1458);
DISPLAY 0.680851 (-1038 1458);
PAINT GREEN (-1038 1458);
FORCEPROP 2 LAST CDS_LIB standard
J 0
(-1100 1450);
DISPLAY INVISIBLE (-1100 1450);
FORCEPROP 1 LAST BODY_TYPE PLUMBING
J 2
(-1100 1500);
DISPLAY 0.872340 (-1100 1500);
PAINT GREEN (-1100 1500);
DISPLAY INVISIBLE (-1100 1500);
FORCEPROP 1 LAST HDL_TAP TRUE
J 2
(-1425 1325);
DISPLAY 0.872340 (-1425 1325);
DISPLAY INVISIBLE (-1425 1325);
FORCEPROP 1 LAST PATH I34
J 2
(-1098 1450);
DISPLAY 0.872340 (-1098 1450);
PAINT GREEN (-1098 1450);
DISPLAY INVISIBLE (-1098 1450);
FORCEADD TAP..1
R 2
(-1100 1600);
FORCEPROP 3 LASTPIN (-1050 1600) SIG_NAME M_A_CPU1_SB_DQ<18>
J 0
(-1040 1610);
DISPLAY 0.659574 (-1040 1610);
PAINT MONO (-1040 1610);
DISPLAY INVISIBLE (-1040 1610);
FORCEPROP 1 LASTPIN (-1050 1600) BN 18
J 2
(-1038 1608);
DISPLAY 0.680851 (-1038 1608);
PAINT GREEN (-1038 1608);
FORCEPROP 2 LAST CDS_LIB standard
J 0
(-1100 1600);
DISPLAY INVISIBLE (-1100 1600);
FORCEPROP 1 LAST BODY_TYPE PLUMBING
J 2
(-1100 1650);
DISPLAY 0.872340 (-1100 1650);
PAINT GREEN (-1100 1650);
DISPLAY INVISIBLE (-1100 1650);
FORCEPROP 1 LAST HDL_TAP TRUE
J 2
(-1425 1475);
DISPLAY 0.872340 (-1425 1475);
DISPLAY INVISIBLE (-1425 1475);
FORCEPROP 1 LAST PATH I35
J 2
(-1098 1600);
DISPLAY 0.872340 (-1098 1600);
PAINT GREEN (-1098 1600);
DISPLAY INVISIBLE (-1098 1600);
FORCEADD TAP..1
R 2
(-1100 1650);
FORCEPROP 3 LASTPIN (-1050 1650) SIG_NAME M_A_CPU1_SB_DQ<19>
J 0
(-1040 1660);
DISPLAY 0.659574 (-1040 1660);
PAINT MONO (-1040 1660);
DISPLAY INVISIBLE (-1040 1660);
FORCEPROP 1 LASTPIN (-1050 1650) BN 19
J 2
(-1038 1658);
DISPLAY 0.680851 (-1038 1658);
PAINT GREEN (-1038 1658);
FORCEPROP 2 LAST CDS_LIB standard
J 0
(-1100 1650);
DISPLAY INVISIBLE (-1100 1650);
FORCEPROP 1 LAST BODY_TYPE PLUMBING
J 2
(-1100 1700);
DISPLAY 0.872340 (-1100 1700);
PAINT GREEN (-1100 1700);
DISPLAY INVISIBLE (-1100 1700);
FORCEPROP 1 LAST HDL_TAP TRUE
J 2
(-1425 1525);
DISPLAY 0.872340 (-1425 1525);
DISPLAY INVISIBLE (-1425 1525);
FORCEPROP 1 LAST PATH I36
J 2
(-1098 1650);
DISPLAY 0.872340 (-1098 1650);
PAINT GREEN (-1098 1650);
DISPLAY INVISIBLE (-1098 1650);
FORCEADD TAP..1
R 2
(-1100 1750);
FORCEPROP 3 LASTPIN (-1050 1750) SIG_NAME M_A_CPU1_SB_DQ<21>
J 0
(-1040 1760);
DISPLAY 0.659574 (-1040 1760);
PAINT MONO (-1040 1760);
DISPLAY INVISIBLE (-1040 1760);
FORCEPROP 1 LASTPIN (-1050 1750) BN 21
J 2
(-1038 1758);
DISPLAY 0.680851 (-1038 1758);
PAINT GREEN (-1038 1758);
FORCEPROP 2 LAST CDS_LIB standard
J 0
(-1100 1750);
DISPLAY INVISIBLE (-1100 1750);
FORCEPROP 1 LAST BODY_TYPE PLUMBING
J 2
(-1100 1800);
DISPLAY 0.872340 (-1100 1800);
PAINT GREEN (-1100 1800);
DISPLAY INVISIBLE (-1100 1800);
FORCEPROP 1 LAST HDL_TAP TRUE
J 2
(-1425 1625);
DISPLAY 0.872340 (-1425 1625);
DISPLAY INVISIBLE (-1425 1625);
FORCEPROP 1 LAST PATH I37
J 2
(-1098 1750);
DISPLAY 0.872340 (-1098 1750);
PAINT GREEN (-1098 1750);
DISPLAY INVISIBLE (-1098 1750);
FORCEADD TAP..1
R 2
(-1100 1800);
FORCEPROP 3 LASTPIN (-1050 1800) SIG_NAME M_A_CPU1_SB_DQ<22>
J 0
(-1040 1810);
DISPLAY 0.659574 (-1040 1810);
PAINT MONO (-1040 1810);
DISPLAY INVISIBLE (-1040 1810);
FORCEPROP 1 LASTPIN (-1050 1800) BN 22
J 2
(-1038 1808);
DISPLAY 0.680851 (-1038 1808);
PAINT GREEN (-1038 1808);
FORCEPROP 2 LAST CDS_LIB standard
J 0
(-1100 1800);
DISPLAY INVISIBLE (-1100 1800);
FORCEPROP 1 LAST BODY_TYPE PLUMBING
J 2
(-1100 1850);
DISPLAY 0.872340 (-1100 1850);
PAINT GREEN (-1100 1850);
DISPLAY INVISIBLE (-1100 1850);
FORCEPROP 1 LAST HDL_TAP TRUE
J 2
(-1425 1675);
DISPLAY 0.872340 (-1425 1675);
DISPLAY INVISIBLE (-1425 1675);
FORCEPROP 1 LAST PATH I38
J 2
(-1098 1800);
DISPLAY 0.872340 (-1098 1800);
PAINT GREEN (-1098 1800);
DISPLAY INVISIBLE (-1098 1800);
FORCEADD TAP..1
R 2
(-1100 1700);
FORCEPROP 3 LASTPIN (-1050 1700) SIG_NAME M_A_CPU1_SB_DQ<20>
J 0
(-1040 1710);
DISPLAY 0.659574 (-1040 1710);
PAINT MONO (-1040 1710);
DISPLAY INVISIBLE (-1040 1710);
FORCEPROP 1 LASTPIN (-1050 1700) BN 20
J 2
(-1038 1708);
DISPLAY 0.680851 (-1038 1708);
PAINT GREEN (-1038 1708);
FORCEPROP 2 LAST CDS_LIB standard
J 0
(-1100 1700);
DISPLAY INVISIBLE (-1100 1700);
FORCEPROP 1 LAST BODY_TYPE PLUMBING
J 2
(-1100 1750);
DISPLAY 0.872340 (-1100 1750);
PAINT GREEN (-1100 1750);
DISPLAY INVISIBLE (-1100 1750);
FORCEPROP 1 LAST HDL_TAP TRUE
J 2
(-1425 1575);
DISPLAY 0.872340 (-1425 1575);
DISPLAY INVISIBLE (-1425 1575);
FORCEPROP 1 LAST PATH I39
J 2
(-1098 1700);
DISPLAY 0.872340 (-1098 1700);
PAINT GREEN (-1098 1700);
DISPLAY INVISIBLE (-1098 1700);
FORCEADD OFFPAGE..2
R 2
(-2125 125);
FORCEPROP 2 LAST $XR1 99 
J 0
(-2469 125);
DISPLAY 0.638298 (-2469 125);
PAINT MONO (-2469 125);
FORCEPROP 2 LAST $XR0 98 
J 0
(-2379 125);
DISPLAY 0.638298 (-2379 125);
PAINT MONO (-2379 125);
FORCEPROP 2 LAST CDS_LIB standard
J 0
(-2125 125);
PAINT MONO (-2125 125);
DISPLAY INVISIBLE (-2125 125);
FORCEPROP 1 LAST OFFPAGE TRUE
J 2
(-2450 0);
DISPLAY 0.872340 (-2450 0);
DISPLAY INVISIBLE (-2450 0);
FORCEPROP 1 LAST COMMENT_BODY TRUE
J 2
(-2080 30);
DISPLAY 0.872340 (-2080 30);
PAINT GREEN (-2080 30);
DISPLAY INVISIBLE (-2080 30);
FORCEPROP 2 LAST PATH I4
J 0
(-2075 200);
DISPLAY 1.021277 (-2075 200);
DISPLAY INVISIBLE (-2075 200);
FORCEADD TAP..1
R 2
(-1100 1850);
FORCEPROP 3 LASTPIN (-1050 1850) SIG_NAME M_A_CPU1_SB_DQ<23>
J 0
(-1040 1860);
DISPLAY 0.659574 (-1040 1860);
PAINT MONO (-1040 1860);
DISPLAY INVISIBLE (-1040 1860);
FORCEPROP 1 LASTPIN (-1050 1850) BN 23
J 2
(-1038 1858);
DISPLAY 0.680851 (-1038 1858);
PAINT GREEN (-1038 1858);
FORCEPROP 2 LAST CDS_LIB standard
J 0
(-1100 1850);
DISPLAY INVISIBLE (-1100 1850);
FORCEPROP 1 LAST BODY_TYPE PLUMBING
J 2
(-1100 1900);
DISPLAY 0.872340 (-1100 1900);
PAINT GREEN (-1100 1900);
DISPLAY INVISIBLE (-1100 1900);
FORCEPROP 1 LAST HDL_TAP TRUE
J 2
(-1425 1725);
DISPLAY 0.872340 (-1425 1725);
DISPLAY INVISIBLE (-1425 1725);
FORCEPROP 1 LAST PATH I40
J 2
(-1098 1850);
DISPLAY 0.872340 (-1098 1850);
PAINT GREEN (-1098 1850);
DISPLAY INVISIBLE (-1098 1850);
FORCEADD TAP..1
R 2
(-1100 1900);
FORCEPROP 3 LASTPIN (-1050 1900) SIG_NAME M_A_CPU1_SB_DQ<24>
J 0
(-1040 1910);
DISPLAY 0.659574 (-1040 1910);
PAINT MONO (-1040 1910);
DISPLAY INVISIBLE (-1040 1910);
FORCEPROP 1 LASTPIN (-1050 1900) BN 24
J 2
(-1038 1908);
DISPLAY 0.680851 (-1038 1908);
PAINT GREEN (-1038 1908);
FORCEPROP 2 LAST CDS_LIB standard
J 0
(-1100 1900);
DISPLAY INVISIBLE (-1100 1900);
FORCEPROP 1 LAST BODY_TYPE PLUMBING
J 2
(-1100 1950);
DISPLAY 0.872340 (-1100 1950);
PAINT GREEN (-1100 1950);
DISPLAY INVISIBLE (-1100 1950);
FORCEPROP 1 LAST HDL_TAP TRUE
J 2
(-1425 1775);
DISPLAY 0.872340 (-1425 1775);
DISPLAY INVISIBLE (-1425 1775);
FORCEPROP 1 LAST PATH I41
J 2
(-1098 1900);
DISPLAY 0.872340 (-1098 1900);
PAINT GREEN (-1098 1900);
DISPLAY INVISIBLE (-1098 1900);
FORCEADD TAP..1
R 2
(-1100 2000);
FORCEPROP 3 LASTPIN (-1050 2000) SIG_NAME M_A_CPU1_SB_DQ<26>
J 0
(-1040 2010);
DISPLAY 0.659574 (-1040 2010);
PAINT MONO (-1040 2010);
DISPLAY INVISIBLE (-1040 2010);
FORCEPROP 1 LASTPIN (-1050 2000) BN 26
J 2
(-1038 2008);
DISPLAY 0.680851 (-1038 2008);
PAINT GREEN (-1038 2008);
FORCEPROP 2 LAST CDS_LIB standard
J 0
(-1100 2000);
DISPLAY INVISIBLE (-1100 2000);
FORCEPROP 1 LAST BODY_TYPE PLUMBING
J 2
(-1100 2050);
DISPLAY 0.872340 (-1100 2050);
PAINT GREEN (-1100 2050);
DISPLAY INVISIBLE (-1100 2050);
FORCEPROP 1 LAST HDL_TAP TRUE
J 2
(-1425 1875);
DISPLAY 0.872340 (-1425 1875);
DISPLAY INVISIBLE (-1425 1875);
FORCEPROP 1 LAST PATH I42
J 2
(-1098 2000);
DISPLAY 0.872340 (-1098 2000);
PAINT GREEN (-1098 2000);
DISPLAY INVISIBLE (-1098 2000);
FORCEADD TAP..1
R 2
(-1100 2050);
FORCEPROP 3 LASTPIN (-1050 2050) SIG_NAME M_A_CPU1_SB_DQ<27>
J 0
(-1040 2060);
DISPLAY 0.659574 (-1040 2060);
PAINT MONO (-1040 2060);
DISPLAY INVISIBLE (-1040 2060);
FORCEPROP 1 LASTPIN (-1050 2050) BN 27
J 2
(-1038 2058);
DISPLAY 0.680851 (-1038 2058);
PAINT GREEN (-1038 2058);
FORCEPROP 2 LAST CDS_LIB standard
J 0
(-1100 2050);
DISPLAY INVISIBLE (-1100 2050);
FORCEPROP 1 LAST BODY_TYPE PLUMBING
J 2
(-1100 2100);
DISPLAY 0.872340 (-1100 2100);
PAINT GREEN (-1100 2100);
DISPLAY INVISIBLE (-1100 2100);
FORCEPROP 1 LAST HDL_TAP TRUE
J 2
(-1425 1925);
DISPLAY 0.872340 (-1425 1925);
DISPLAY INVISIBLE (-1425 1925);
FORCEPROP 1 LAST PATH I43
J 2
(-1098 2050);
DISPLAY 0.872340 (-1098 2050);
PAINT GREEN (-1098 2050);
DISPLAY INVISIBLE (-1098 2050);
FORCEADD TAP..1
R 2
(-1100 1950);
FORCEPROP 3 LASTPIN (-1050 1950) SIG_NAME M_A_CPU1_SB_DQ<25>
J 0
(-1040 1960);
DISPLAY 0.659574 (-1040 1960);
PAINT MONO (-1040 1960);
DISPLAY INVISIBLE (-1040 1960);
FORCEPROP 1 LASTPIN (-1050 1950) BN 25
J 2
(-1038 1958);
DISPLAY 0.680851 (-1038 1958);
PAINT GREEN (-1038 1958);
FORCEPROP 2 LAST CDS_LIB standard
J 0
(-1100 1950);
DISPLAY INVISIBLE (-1100 1950);
FORCEPROP 1 LAST BODY_TYPE PLUMBING
J 2
(-1100 2000);
DISPLAY 0.872340 (-1100 2000);
PAINT GREEN (-1100 2000);
DISPLAY INVISIBLE (-1100 2000);
FORCEPROP 1 LAST HDL_TAP TRUE
J 2
(-1425 1825);
DISPLAY 0.872340 (-1425 1825);
DISPLAY INVISIBLE (-1425 1825);
FORCEPROP 1 LAST PATH I44
J 2
(-1098 1950);
DISPLAY 0.872340 (-1098 1950);
PAINT GREEN (-1098 1950);
DISPLAY INVISIBLE (-1098 1950);
FORCEADD OFFPAGE..3
R 2
(-2125 2275);
FORCEPROP 2 LAST $XR1 99 
J 0
(-2494 2275);
DISPLAY 0.638298 (-2494 2275);
PAINT MONO (-2494 2275);
FORCEPROP 2 LAST $XR0 98 
J 0
(-2404 2275);
DISPLAY 0.638298 (-2404 2275);
PAINT MONO (-2404 2275);
FORCEPROP 2 LAST CDS_LIB standard
J 0
(-2125 2275);
DISPLAY INVISIBLE (-2125 2275);
FORCEPROP 1 LAST OFFPAGE TRUE
J 2
(-2450 2150);
DISPLAY 0.872340 (-2450 2150);
DISPLAY INVISIBLE (-2450 2150);
FORCEPROP 1 LAST COMMENT_BODY TRUE
J 2
(-2075 2175);
DISPLAY 0.872340 (-2075 2175);
PAINT GREEN (-2075 2175);
DISPLAY INVISIBLE (-2075 2175);
FORCEPROP 2 LAST PATH I45
J 0
(-2075 2350);
DISPLAY 1.021277 (-2075 2350);
DISPLAY INVISIBLE (-2075 2350);
FORCEADD OFFPAGE..3
R 2
(-2125 2675);
FORCEPROP 2 LAST $XR1 99 
J 0
(-2494 2675);
DISPLAY 0.638298 (-2494 2675);
PAINT MONO (-2494 2675);
FORCEPROP 2 LAST $XR0 98 
J 0
(-2404 2675);
DISPLAY 0.638298 (-2404 2675);
PAINT MONO (-2404 2675);
FORCEPROP 2 LAST CDS_LIB standard
J 0
(-2125 2675);
DISPLAY INVISIBLE (-2125 2675);
FORCEPROP 1 LAST OFFPAGE TRUE
J 2
(-2450 2550);
DISPLAY 0.872340 (-2450 2550);
DISPLAY INVISIBLE (-2450 2550);
FORCEPROP 1 LAST COMMENT_BODY TRUE
J 2
(-2075 2575);
DISPLAY 0.872340 (-2075 2575);
PAINT GREEN (-2075 2575);
DISPLAY INVISIBLE (-2075 2575);
FORCEPROP 2 LAST PATH I46
J 0
(-2075 2750);
DISPLAY 1.021277 (-2075 2750);
DISPLAY INVISIBLE (-2075 2750);
FORCEADD TAP..1
R 2
(-1100 2200);
FORCEPROP 3 LASTPIN (-1050 2200) SIG_NAME M_A_CPU1_SB_DQ<30>
J 0
(-1040 2210);
DISPLAY 0.659574 (-1040 2210);
PAINT MONO (-1040 2210);
DISPLAY INVISIBLE (-1040 2210);
FORCEPROP 1 LASTPIN (-1050 2200) BN 30
J 2
(-1038 2208);
DISPLAY 0.680851 (-1038 2208);
PAINT GREEN (-1038 2208);
FORCEPROP 2 LAST CDS_LIB standard
J 0
(-1100 2200);
DISPLAY INVISIBLE (-1100 2200);
FORCEPROP 1 LAST BODY_TYPE PLUMBING
J 2
(-1100 2250);
DISPLAY 0.872340 (-1100 2250);
PAINT GREEN (-1100 2250);
DISPLAY INVISIBLE (-1100 2250);
FORCEPROP 1 LAST HDL_TAP TRUE
J 2
(-1425 2075);
DISPLAY 0.872340 (-1425 2075);
DISPLAY INVISIBLE (-1425 2075);
FORCEPROP 1 LAST PATH I47
J 2
(-1098 2200);
DISPLAY 0.872340 (-1098 2200);
PAINT GREEN (-1098 2200);
DISPLAY INVISIBLE (-1098 2200);
FORCEADD TAP..1
R 2
(-1100 2150);
FORCEPROP 3 LASTPIN (-1050 2150) SIG_NAME M_A_CPU1_SB_DQ<29>
J 0
(-1040 2160);
DISPLAY 0.659574 (-1040 2160);
PAINT MONO (-1040 2160);
DISPLAY INVISIBLE (-1040 2160);
FORCEPROP 1 LASTPIN (-1050 2150) BN 29
J 2
(-1038 2158);
DISPLAY 0.680851 (-1038 2158);
PAINT GREEN (-1038 2158);
FORCEPROP 2 LAST CDS_LIB standard
J 0
(-1100 2150);
DISPLAY INVISIBLE (-1100 2150);
FORCEPROP 1 LAST BODY_TYPE PLUMBING
J 2
(-1100 2200);
DISPLAY 0.872340 (-1100 2200);
PAINT GREEN (-1100 2200);
DISPLAY INVISIBLE (-1100 2200);
FORCEPROP 1 LAST HDL_TAP TRUE
J 2
(-1425 2025);
DISPLAY 0.872340 (-1425 2025);
DISPLAY INVISIBLE (-1425 2025);
FORCEPROP 1 LAST PATH I48
J 2
(-1098 2150);
DISPLAY 0.872340 (-1098 2150);
PAINT GREEN (-1098 2150);
DISPLAY INVISIBLE (-1098 2150);
FORCEADD TAP..1
R 2
(-1100 2100);
FORCEPROP 3 LASTPIN (-1050 2100) SIG_NAME M_A_CPU1_SB_DQ<28>
J 0
(-1040 2110);
DISPLAY 0.659574 (-1040 2110);
PAINT MONO (-1040 2110);
DISPLAY INVISIBLE (-1040 2110);
FORCEPROP 1 LASTPIN (-1050 2100) BN 28
J 2
(-1038 2108);
DISPLAY 0.680851 (-1038 2108);
PAINT GREEN (-1038 2108);
FORCEPROP 2 LAST CDS_LIB standard
J 0
(-1100 2100);
DISPLAY INVISIBLE (-1100 2100);
FORCEPROP 1 LAST BODY_TYPE PLUMBING
J 2
(-1100 2150);
DISPLAY 0.872340 (-1100 2150);
PAINT GREEN (-1100 2150);
DISPLAY INVISIBLE (-1100 2150);
FORCEPROP 1 LAST HDL_TAP TRUE
J 2
(-1425 1975);
DISPLAY 0.872340 (-1425 1975);
DISPLAY INVISIBLE (-1425 1975);
FORCEPROP 1 LAST PATH I49
J 2
(-1098 2100);
DISPLAY 0.872340 (-1098 2100);
PAINT GREEN (-1098 2100);
DISPLAY INVISIBLE (-1098 2100);
FORCEADD OFFPAGE..3
R 2
(-2125 675);
FORCEPROP 2 LAST $XR1 99 
J 0
(-2494 675);
DISPLAY 0.638298 (-2494 675);
PAINT MONO (-2494 675);
FORCEPROP 2 LAST $XR0 98 
J 0
(-2404 675);
DISPLAY 0.638298 (-2404 675);
PAINT MONO (-2404 675);
FORCEPROP 2 LAST CDS_LIB standard
J 0
(-2125 675);
DISPLAY INVISIBLE (-2125 675);
FORCEPROP 1 LAST OFFPAGE TRUE
J 2
(-2450 550);
DISPLAY 0.872340 (-2450 550);
DISPLAY INVISIBLE (-2450 550);
FORCEPROP 1 LAST COMMENT_BODY TRUE
J 2
(-2075 575);
DISPLAY 0.872340 (-2075 575);
PAINT GREEN (-2075 575);
DISPLAY INVISIBLE (-2075 575);
FORCEPROP 2 LAST PATH I5
J 0
(-2075 750);
DISPLAY 1.021277 (-2075 750);
DISPLAY INVISIBLE (-2075 750);
FORCEADD TAP..1
R 2
(-1100 2250);
FORCEPROP 3 LASTPIN (-1050 2250) SIG_NAME M_A_CPU1_SB_DQ<31>
J 0
(-1040 2260);
DISPLAY 0.659574 (-1040 2260);
PAINT MONO (-1040 2260);
DISPLAY INVISIBLE (-1040 2260);
FORCEPROP 1 LASTPIN (-1050 2250) BN 31
J 2
(-1038 2258);
DISPLAY 0.680851 (-1038 2258);
PAINT GREEN (-1038 2258);
FORCEPROP 2 LAST CDS_LIB standard
J 0
(-1100 2250);
DISPLAY INVISIBLE (-1100 2250);
FORCEPROP 1 LAST BODY_TYPE PLUMBING
J 2
(-1100 2300);
DISPLAY 0.872340 (-1100 2300);
PAINT GREEN (-1100 2300);
DISPLAY INVISIBLE (-1100 2300);
FORCEPROP 1 LAST HDL_TAP TRUE
J 2
(-1425 2125);
DISPLAY 0.872340 (-1425 2125);
DISPLAY INVISIBLE (-1425 2125);
FORCEPROP 1 LAST PATH I50
J 2
(-1098 2250);
DISPLAY 0.872340 (-1098 2250);
PAINT GREEN (-1098 2250);
DISPLAY INVISIBLE (-1098 2250);
FORCEADD TAP..1
R 2
(-1100 2300);
FORCEPROP 3 LASTPIN (-1050 2300) SIG_NAME M_A_CPU1_SA_CB<0>
J 0
(-1040 2310);
DISPLAY 0.659574 (-1040 2310);
PAINT MONO (-1040 2310);
DISPLAY INVISIBLE (-1040 2310);
FORCEPROP 1 LASTPIN (-1050 2300) BN 0
J 2
(-1038 2308);
DISPLAY 0.680851 (-1038 2308);
PAINT GREEN (-1038 2308);
FORCEPROP 2 LAST CDS_LIB standard
J 0
(-1100 2300);
DISPLAY INVISIBLE (-1100 2300);
FORCEPROP 1 LAST BODY_TYPE PLUMBING
J 2
(-1100 2350);
DISPLAY 0.872340 (-1100 2350);
PAINT GREEN (-1100 2350);
DISPLAY INVISIBLE (-1100 2350);
FORCEPROP 1 LAST HDL_TAP TRUE
J 2
(-1425 2175);
DISPLAY 0.872340 (-1425 2175);
DISPLAY INVISIBLE (-1425 2175);
FORCEPROP 1 LAST PATH I51
J 2
(-1098 2300);
DISPLAY 0.872340 (-1098 2300);
PAINT GREEN (-1098 2300);
DISPLAY INVISIBLE (-1098 2300);
FORCEADD TAP..1
R 2
(-1100 2350);
FORCEPROP 3 LASTPIN (-1050 2350) SIG_NAME M_A_CPU1_SA_CB<1>
J 0
(-1040 2360);
DISPLAY 0.659574 (-1040 2360);
PAINT MONO (-1040 2360);
DISPLAY INVISIBLE (-1040 2360);
FORCEPROP 1 LASTPIN (-1050 2350) BN 1
J 2
(-1038 2358);
DISPLAY 0.680851 (-1038 2358);
PAINT GREEN (-1038 2358);
FORCEPROP 2 LAST CDS_LIB standard
J 0
(-1100 2350);
DISPLAY INVISIBLE (-1100 2350);
FORCEPROP 1 LAST BODY_TYPE PLUMBING
J 2
(-1100 2400);
DISPLAY 0.872340 (-1100 2400);
PAINT GREEN (-1100 2400);
DISPLAY INVISIBLE (-1100 2400);
FORCEPROP 1 LAST HDL_TAP TRUE
J 2
(-1425 2225);
DISPLAY 0.872340 (-1425 2225);
DISPLAY INVISIBLE (-1425 2225);
FORCEPROP 1 LAST PATH I52
J 2
(-1098 2350);
DISPLAY 0.872340 (-1098 2350);
PAINT GREEN (-1098 2350);
DISPLAY INVISIBLE (-1098 2350);
FORCEADD TAP..1
R 2
(-1100 2400);
FORCEPROP 3 LASTPIN (-1050 2400) SIG_NAME M_A_CPU1_SA_CB<2>
J 0
(-1040 2410);
DISPLAY 0.659574 (-1040 2410);
PAINT MONO (-1040 2410);
DISPLAY INVISIBLE (-1040 2410);
FORCEPROP 1 LASTPIN (-1050 2400) BN 2
J 2
(-1038 2408);
DISPLAY 0.680851 (-1038 2408);
PAINT GREEN (-1038 2408);
FORCEPROP 2 LAST CDS_LIB standard
J 0
(-1100 2400);
DISPLAY INVISIBLE (-1100 2400);
FORCEPROP 1 LAST BODY_TYPE PLUMBING
J 2
(-1100 2450);
DISPLAY 0.872340 (-1100 2450);
PAINT GREEN (-1100 2450);
DISPLAY INVISIBLE (-1100 2450);
FORCEPROP 1 LAST HDL_TAP TRUE
J 2
(-1425 2275);
DISPLAY 0.872340 (-1425 2275);
DISPLAY INVISIBLE (-1425 2275);
FORCEPROP 1 LAST PATH I53
J 2
(-1098 2400);
DISPLAY 0.872340 (-1098 2400);
PAINT GREEN (-1098 2400);
DISPLAY INVISIBLE (-1098 2400);
FORCEADD TAP..1
R 2
(-1100 2450);
FORCEPROP 3 LASTPIN (-1050 2450) SIG_NAME M_A_CPU1_SA_CB<3>
J 0
(-1040 2460);
DISPLAY 0.659574 (-1040 2460);
PAINT MONO (-1040 2460);
DISPLAY INVISIBLE (-1040 2460);
FORCEPROP 1 LASTPIN (-1050 2450) BN 3
J 2
(-1038 2458);
DISPLAY 0.680851 (-1038 2458);
PAINT GREEN (-1038 2458);
FORCEPROP 2 LAST CDS_LIB standard
J 0
(-1100 2450);
DISPLAY INVISIBLE (-1100 2450);
FORCEPROP 1 LAST BODY_TYPE PLUMBING
J 2
(-1100 2500);
DISPLAY 0.872340 (-1100 2500);
PAINT GREEN (-1100 2500);
DISPLAY INVISIBLE (-1100 2500);
FORCEPROP 1 LAST HDL_TAP TRUE
J 2
(-1425 2325);
DISPLAY 0.872340 (-1425 2325);
DISPLAY INVISIBLE (-1425 2325);
FORCEPROP 1 LAST PATH I54
J 2
(-1098 2450);
DISPLAY 0.872340 (-1098 2450);
PAINT GREEN (-1098 2450);
DISPLAY INVISIBLE (-1098 2450);
FORCEADD TAP..1
R 2
(-1100 2500);
FORCEPROP 3 LASTPIN (-1050 2500) SIG_NAME M_A_CPU1_SA_CB<4>
J 0
(-1040 2510);
DISPLAY 0.659574 (-1040 2510);
PAINT MONO (-1040 2510);
DISPLAY INVISIBLE (-1040 2510);
FORCEPROP 1 LASTPIN (-1050 2500) BN 4
J 2
(-1038 2508);
DISPLAY 0.680851 (-1038 2508);
PAINT GREEN (-1038 2508);
FORCEPROP 2 LAST CDS_LIB standard
J 0
(-1100 2500);
DISPLAY INVISIBLE (-1100 2500);
FORCEPROP 1 LAST BODY_TYPE PLUMBING
J 2
(-1100 2550);
DISPLAY 0.872340 (-1100 2550);
PAINT GREEN (-1100 2550);
DISPLAY INVISIBLE (-1100 2550);
FORCEPROP 1 LAST HDL_TAP TRUE
J 2
(-1425 2375);
DISPLAY 0.872340 (-1425 2375);
DISPLAY INVISIBLE (-1425 2375);
FORCEPROP 1 LAST PATH I55
J 2
(-1098 2500);
DISPLAY 0.872340 (-1098 2500);
PAINT GREEN (-1098 2500);
DISPLAY INVISIBLE (-1098 2500);
FORCEADD TAP..1
R 2
(-1100 2550);
FORCEPROP 3 LASTPIN (-1050 2550) SIG_NAME M_A_CPU1_SA_CB<5>
J 0
(-1040 2560);
DISPLAY 0.659574 (-1040 2560);
PAINT MONO (-1040 2560);
DISPLAY INVISIBLE (-1040 2560);
FORCEPROP 1 LASTPIN (-1050 2550) BN 5
J 2
(-1038 2558);
DISPLAY 0.680851 (-1038 2558);
PAINT GREEN (-1038 2558);
FORCEPROP 2 LAST CDS_LIB standard
J 0
(-1100 2550);
DISPLAY INVISIBLE (-1100 2550);
FORCEPROP 1 LAST BODY_TYPE PLUMBING
J 2
(-1100 2600);
DISPLAY 0.872340 (-1100 2600);
PAINT GREEN (-1100 2600);
DISPLAY INVISIBLE (-1100 2600);
FORCEPROP 1 LAST HDL_TAP TRUE
J 2
(-1425 2425);
DISPLAY 0.872340 (-1425 2425);
DISPLAY INVISIBLE (-1425 2425);
FORCEPROP 1 LAST PATH I56
J 2
(-1098 2550);
DISPLAY 0.872340 (-1098 2550);
PAINT GREEN (-1098 2550);
DISPLAY INVISIBLE (-1098 2550);
FORCEADD TAP..1
R 2
(-1100 2600);
FORCEPROP 3 LASTPIN (-1050 2600) SIG_NAME M_A_CPU1_SA_CB<6>
J 0
(-1040 2610);
DISPLAY 0.659574 (-1040 2610);
PAINT MONO (-1040 2610);
DISPLAY INVISIBLE (-1040 2610);
FORCEPROP 1 LASTPIN (-1050 2600) BN 6
J 2
(-1038 2608);
DISPLAY 0.680851 (-1038 2608);
PAINT GREEN (-1038 2608);
FORCEPROP 2 LAST CDS_LIB standard
J 0
(-1100 2600);
DISPLAY INVISIBLE (-1100 2600);
FORCEPROP 1 LAST BODY_TYPE PLUMBING
J 2
(-1100 2650);
DISPLAY 0.872340 (-1100 2650);
PAINT GREEN (-1100 2650);
DISPLAY INVISIBLE (-1100 2650);
FORCEPROP 1 LAST HDL_TAP TRUE
J 2
(-1425 2475);
DISPLAY 0.872340 (-1425 2475);
DISPLAY INVISIBLE (-1425 2475);
FORCEPROP 1 LAST PATH I57
J 2
(-1098 2600);
DISPLAY 0.872340 (-1098 2600);
PAINT GREEN (-1098 2600);
DISPLAY INVISIBLE (-1098 2600);
FORCEADD TAP..1
R 2
(-1100 2650);
FORCEPROP 3 LASTPIN (-1050 2650) SIG_NAME M_A_CPU1_SA_CB<7>
J 0
(-1040 2660);
DISPLAY 0.659574 (-1040 2660);
PAINT MONO (-1040 2660);
DISPLAY INVISIBLE (-1040 2660);
FORCEPROP 1 LASTPIN (-1050 2650) BN 7
J 2
(-1038 2658);
DISPLAY 0.680851 (-1038 2658);
PAINT GREEN (-1038 2658);
FORCEPROP 2 LAST CDS_LIB standard
J 0
(-1100 2650);
DISPLAY INVISIBLE (-1100 2650);
FORCEPROP 1 LAST BODY_TYPE PLUMBING
J 2
(-1100 2700);
DISPLAY 0.872340 (-1100 2700);
PAINT GREEN (-1100 2700);
DISPLAY INVISIBLE (-1100 2700);
FORCEPROP 1 LAST HDL_TAP TRUE
J 2
(-1425 2525);
DISPLAY 0.872340 (-1425 2525);
DISPLAY INVISIBLE (-1425 2525);
FORCEPROP 1 LAST PATH I58
J 2
(-1098 2650);
DISPLAY 0.872340 (-1098 2650);
PAINT GREEN (-1098 2650);
DISPLAY INVISIBLE (-1098 2650);
FORCEADD TAP..1
R 2
(-1100 2700);
FORCEPROP 3 LASTPIN (-1050 2700) SIG_NAME M_A_CPU1_SA_DQ<0>
J 0
(-1040 2710);
DISPLAY 0.659574 (-1040 2710);
PAINT MONO (-1040 2710);
DISPLAY INVISIBLE (-1040 2710);
FORCEPROP 1 LASTPIN (-1050 2700) BN 0
J 2
(-1038 2708);
DISPLAY 0.680851 (-1038 2708);
PAINT GREEN (-1038 2708);
FORCEPROP 2 LAST CDS_LIB standard
J 0
(-1100 2700);
DISPLAY INVISIBLE (-1100 2700);
FORCEPROP 1 LAST BODY_TYPE PLUMBING
J 2
(-1100 2750);
DISPLAY 0.872340 (-1100 2750);
PAINT GREEN (-1100 2750);
DISPLAY INVISIBLE (-1100 2750);
FORCEPROP 1 LAST HDL_TAP TRUE
J 2
(-1425 2575);
DISPLAY 0.872340 (-1425 2575);
DISPLAY INVISIBLE (-1425 2575);
FORCEPROP 1 LAST PATH I59
J 2
(-1098 2700);
DISPLAY 0.872340 (-1098 2700);
PAINT GREEN (-1098 2700);
DISPLAY INVISIBLE (-1098 2700);
FORCEADD TAP..1
R 2
(-1100 200);
FORCEPROP 3 LASTPIN (-1050 200) SIG_NAME M_A_CPU1_CLK_DP<1>
J 0
(-1040 210);
DISPLAY 0.659574 (-1040 210);
PAINT MONO (-1040 210);
DISPLAY INVISIBLE (-1040 210);
FORCEPROP 1 LASTPIN (-1050 200) BN 1
J 2
(-1038 208);
DISPLAY 0.680851 (-1038 208);
PAINT GREEN (-1038 208);
FORCEPROP 2 LAST CDS_LIB standard
J 0
(-1100 200);
DISPLAY INVISIBLE (-1100 200);
FORCEPROP 1 LAST BODY_TYPE PLUMBING
J 2
(-1100 250);
DISPLAY 0.872340 (-1100 250);
PAINT GREEN (-1100 250);
DISPLAY INVISIBLE (-1100 250);
FORCEPROP 1 LAST HDL_TAP TRUE
J 2
(-1425 75);
DISPLAY 0.872340 (-1425 75);
DISPLAY INVISIBLE (-1425 75);
FORCEPROP 1 LAST PATH I6
J 2
(-1098 200);
DISPLAY 0.872340 (-1098 200);
PAINT GREEN (-1098 200);
DISPLAY INVISIBLE (-1098 200);
FORCEADD TAP..1
R 2
(-1100 2800);
FORCEPROP 3 LASTPIN (-1050 2800) SIG_NAME M_A_CPU1_SA_DQ<2>
J 0
(-1040 2810);
DISPLAY 0.659574 (-1040 2810);
PAINT MONO (-1040 2810);
DISPLAY INVISIBLE (-1040 2810);
FORCEPROP 1 LASTPIN (-1050 2800) BN 2
J 2
(-1038 2808);
DISPLAY 0.680851 (-1038 2808);
PAINT GREEN (-1038 2808);
FORCEPROP 2 LAST CDS_LIB standard
J 0
(-1100 2800);
DISPLAY INVISIBLE (-1100 2800);
FORCEPROP 1 LAST BODY_TYPE PLUMBING
J 2
(-1100 2850);
DISPLAY 0.872340 (-1100 2850);
PAINT GREEN (-1100 2850);
DISPLAY INVISIBLE (-1100 2850);
FORCEPROP 1 LAST HDL_TAP TRUE
J 2
(-1425 2675);
DISPLAY 0.872340 (-1425 2675);
DISPLAY INVISIBLE (-1425 2675);
FORCEPROP 1 LAST PATH I60
J 2
(-1098 2800);
DISPLAY 0.872340 (-1098 2800);
PAINT GREEN (-1098 2800);
DISPLAY INVISIBLE (-1098 2800);
FORCEADD TAP..1
R 2
(-1100 2750);
FORCEPROP 3 LASTPIN (-1050 2750) SIG_NAME M_A_CPU1_SA_DQ<1>
J 0
(-1040 2760);
DISPLAY 0.659574 (-1040 2760);
PAINT MONO (-1040 2760);
DISPLAY INVISIBLE (-1040 2760);
FORCEPROP 1 LASTPIN (-1050 2750) BN 1
J 2
(-1038 2758);
DISPLAY 0.680851 (-1038 2758);
PAINT GREEN (-1038 2758);
FORCEPROP 2 LAST CDS_LIB standard
J 0
(-1100 2750);
DISPLAY INVISIBLE (-1100 2750);
FORCEPROP 1 LAST BODY_TYPE PLUMBING
J 2
(-1100 2800);
DISPLAY 0.872340 (-1100 2800);
PAINT GREEN (-1100 2800);
DISPLAY INVISIBLE (-1100 2800);
FORCEPROP 1 LAST HDL_TAP TRUE
J 2
(-1425 2625);
DISPLAY 0.872340 (-1425 2625);
DISPLAY INVISIBLE (-1425 2625);
FORCEPROP 1 LAST PATH I61
J 2
(-1098 2750);
DISPLAY 0.872340 (-1098 2750);
PAINT GREEN (-1098 2750);
DISPLAY INVISIBLE (-1098 2750);
FORCEADD TAP..1
R 2
(-1100 2850);
FORCEPROP 3 LASTPIN (-1050 2850) SIG_NAME M_A_CPU1_SA_DQ<3>
J 0
(-1040 2860);
DISPLAY 0.659574 (-1040 2860);
PAINT MONO (-1040 2860);
DISPLAY INVISIBLE (-1040 2860);
FORCEPROP 1 LASTPIN (-1050 2850) BN 3
J 2
(-1038 2858);
DISPLAY 0.680851 (-1038 2858);
PAINT GREEN (-1038 2858);
FORCEPROP 2 LAST CDS_LIB standard
J 0
(-1100 2850);
DISPLAY INVISIBLE (-1100 2850);
FORCEPROP 1 LAST BODY_TYPE PLUMBING
J 2
(-1100 2900);
DISPLAY 0.872340 (-1100 2900);
PAINT GREEN (-1100 2900);
DISPLAY INVISIBLE (-1100 2900);
FORCEPROP 1 LAST HDL_TAP TRUE
J 2
(-1425 2725);
DISPLAY 0.872340 (-1425 2725);
DISPLAY INVISIBLE (-1425 2725);
FORCEPROP 1 LAST PATH I62
J 2
(-1098 2850);
DISPLAY 0.872340 (-1098 2850);
PAINT GREEN (-1098 2850);
DISPLAY INVISIBLE (-1098 2850);
FORCEADD TAP..1
R 2
(-1100 2900);
FORCEPROP 3 LASTPIN (-1050 2900) SIG_NAME M_A_CPU1_SA_DQ<4>
J 0
(-1040 2910);
DISPLAY 0.659574 (-1040 2910);
PAINT MONO (-1040 2910);
DISPLAY INVISIBLE (-1040 2910);
FORCEPROP 1 LASTPIN (-1050 2900) BN 4
J 2
(-1038 2908);
DISPLAY 0.680851 (-1038 2908);
PAINT GREEN (-1038 2908);
FORCEPROP 2 LAST CDS_LIB standard
J 0
(-1100 2900);
DISPLAY INVISIBLE (-1100 2900);
FORCEPROP 1 LAST BODY_TYPE PLUMBING
J 2
(-1100 2950);
DISPLAY 0.872340 (-1100 2950);
PAINT GREEN (-1100 2950);
DISPLAY INVISIBLE (-1100 2950);
FORCEPROP 1 LAST HDL_TAP TRUE
J 2
(-1425 2775);
DISPLAY 0.872340 (-1425 2775);
DISPLAY INVISIBLE (-1425 2775);
FORCEPROP 1 LAST PATH I63
J 2
(-1098 2900);
DISPLAY 0.872340 (-1098 2900);
PAINT GREEN (-1098 2900);
DISPLAY INVISIBLE (-1098 2900);
FORCEADD TAP..1
R 2
(-1100 2950);
FORCEPROP 3 LASTPIN (-1050 2950) SIG_NAME M_A_CPU1_SA_DQ<5>
J 0
(-1040 2960);
DISPLAY 0.659574 (-1040 2960);
PAINT MONO (-1040 2960);
DISPLAY INVISIBLE (-1040 2960);
FORCEPROP 1 LASTPIN (-1050 2950) BN 5
J 2
(-1038 2958);
DISPLAY 0.680851 (-1038 2958);
PAINT GREEN (-1038 2958);
FORCEPROP 2 LAST CDS_LIB standard
J 0
(-1100 2950);
DISPLAY INVISIBLE (-1100 2950);
FORCEPROP 1 LAST BODY_TYPE PLUMBING
J 2
(-1100 3000);
DISPLAY 0.872340 (-1100 3000);
PAINT GREEN (-1100 3000);
DISPLAY INVISIBLE (-1100 3000);
FORCEPROP 1 LAST HDL_TAP TRUE
J 2
(-1425 2825);
DISPLAY 0.872340 (-1425 2825);
DISPLAY INVISIBLE (-1425 2825);
FORCEPROP 1 LAST PATH I64
J 2
(-1098 2950);
DISPLAY 0.872340 (-1098 2950);
PAINT GREEN (-1098 2950);
DISPLAY INVISIBLE (-1098 2950);
FORCEADD TAP..1
R 2
(-1100 3050);
FORCEPROP 3 LASTPIN (-1050 3050) SIG_NAME M_A_CPU1_SA_DQ<7>
J 0
(-1040 3060);
DISPLAY 0.659574 (-1040 3060);
PAINT MONO (-1040 3060);
DISPLAY INVISIBLE (-1040 3060);
FORCEPROP 1 LASTPIN (-1050 3050) BN 7
J 2
(-1038 3058);
DISPLAY 0.680851 (-1038 3058);
PAINT GREEN (-1038 3058);
FORCEPROP 2 LAST CDS_LIB standard
J 0
(-1100 3050);
DISPLAY INVISIBLE (-1100 3050);
FORCEPROP 1 LAST BODY_TYPE PLUMBING
J 2
(-1100 3100);
DISPLAY 0.872340 (-1100 3100);
PAINT GREEN (-1100 3100);
DISPLAY INVISIBLE (-1100 3100);
FORCEPROP 1 LAST HDL_TAP TRUE
J 2
(-1425 2925);
DISPLAY 0.872340 (-1425 2925);
DISPLAY INVISIBLE (-1425 2925);
FORCEPROP 1 LAST PATH I65
J 2
(-1098 3050);
DISPLAY 0.872340 (-1098 3050);
PAINT GREEN (-1098 3050);
DISPLAY INVISIBLE (-1098 3050);
FORCEADD TAP..1
R 2
(-1100 3000);
FORCEPROP 3 LASTPIN (-1050 3000) SIG_NAME M_A_CPU1_SA_DQ<6>
J 0
(-1040 3010);
DISPLAY 0.659574 (-1040 3010);
PAINT MONO (-1040 3010);
DISPLAY INVISIBLE (-1040 3010);
FORCEPROP 1 LASTPIN (-1050 3000) BN 6
J 2
(-1038 3008);
DISPLAY 0.680851 (-1038 3008);
PAINT GREEN (-1038 3008);
FORCEPROP 2 LAST CDS_LIB standard
J 0
(-1100 3000);
DISPLAY INVISIBLE (-1100 3000);
FORCEPROP 1 LAST BODY_TYPE PLUMBING
J 2
(-1100 3050);
DISPLAY 0.872340 (-1100 3050);
PAINT GREEN (-1100 3050);
DISPLAY INVISIBLE (-1100 3050);
FORCEPROP 1 LAST HDL_TAP TRUE
J 2
(-1425 2875);
DISPLAY 0.872340 (-1425 2875);
DISPLAY INVISIBLE (-1425 2875);
FORCEPROP 1 LAST PATH I66
J 2
(-1098 3000);
DISPLAY 0.872340 (-1098 3000);
PAINT GREEN (-1098 3000);
DISPLAY INVISIBLE (-1098 3000);
FORCEADD TAP..1
R 2
(-1100 3100);
FORCEPROP 3 LASTPIN (-1050 3100) SIG_NAME M_A_CPU1_SA_DQ<8>
J 0
(-1040 3110);
DISPLAY 0.659574 (-1040 3110);
PAINT MONO (-1040 3110);
DISPLAY INVISIBLE (-1040 3110);
FORCEPROP 1 LASTPIN (-1050 3100) BN 8
J 2
(-1038 3108);
DISPLAY 0.680851 (-1038 3108);
PAINT GREEN (-1038 3108);
FORCEPROP 2 LAST CDS_LIB standard
J 0
(-1100 3100);
DISPLAY INVISIBLE (-1100 3100);
FORCEPROP 1 LAST BODY_TYPE PLUMBING
J 2
(-1100 3150);
DISPLAY 0.872340 (-1100 3150);
PAINT GREEN (-1100 3150);
DISPLAY INVISIBLE (-1100 3150);
FORCEPROP 1 LAST HDL_TAP TRUE
J 2
(-1425 2975);
DISPLAY 0.872340 (-1425 2975);
DISPLAY INVISIBLE (-1425 2975);
FORCEPROP 1 LAST PATH I67
J 2
(-1098 3100);
DISPLAY 0.872340 (-1098 3100);
PAINT GREEN (-1098 3100);
DISPLAY INVISIBLE (-1098 3100);
FORCEADD TAP..1
R 2
(-1100 3150);
FORCEPROP 3 LASTPIN (-1050 3150) SIG_NAME M_A_CPU1_SA_DQ<9>
J 0
(-1040 3160);
DISPLAY 0.659574 (-1040 3160);
PAINT MONO (-1040 3160);
DISPLAY INVISIBLE (-1040 3160);
FORCEPROP 1 LASTPIN (-1050 3150) BN 9
J 2
(-1038 3158);
DISPLAY 0.680851 (-1038 3158);
PAINT GREEN (-1038 3158);
FORCEPROP 2 LAST CDS_LIB standard
J 0
(-1100 3150);
DISPLAY INVISIBLE (-1100 3150);
FORCEPROP 1 LAST BODY_TYPE PLUMBING
J 2
(-1100 3200);
DISPLAY 0.872340 (-1100 3200);
PAINT GREEN (-1100 3200);
DISPLAY INVISIBLE (-1100 3200);
FORCEPROP 1 LAST HDL_TAP TRUE
J 2
(-1425 3025);
DISPLAY 0.872340 (-1425 3025);
DISPLAY INVISIBLE (-1425 3025);
FORCEPROP 1 LAST PATH I68
J 2
(-1098 3150);
DISPLAY 0.872340 (-1098 3150);
PAINT GREEN (-1098 3150);
DISPLAY INVISIBLE (-1098 3150);
FORCEADD TAP..1
R 2
(-1100 3200);
FORCEPROP 3 LASTPIN (-1050 3200) SIG_NAME M_A_CPU1_SA_DQ<10>
J 0
(-1040 3210);
DISPLAY 0.659574 (-1040 3210);
PAINT MONO (-1040 3210);
DISPLAY INVISIBLE (-1040 3210);
FORCEPROP 1 LASTPIN (-1050 3200) BN 10
J 2
(-1038 3208);
DISPLAY 0.680851 (-1038 3208);
PAINT GREEN (-1038 3208);
FORCEPROP 2 LAST CDS_LIB standard
J 0
(-1100 3200);
DISPLAY INVISIBLE (-1100 3200);
FORCEPROP 1 LAST BODY_TYPE PLUMBING
J 2
(-1100 3250);
DISPLAY 0.872340 (-1100 3250);
PAINT GREEN (-1100 3250);
DISPLAY INVISIBLE (-1100 3250);
FORCEPROP 1 LAST HDL_TAP TRUE
J 2
(-1425 3075);
DISPLAY 0.872340 (-1425 3075);
DISPLAY INVISIBLE (-1425 3075);
FORCEPROP 1 LAST PATH I69
J 2
(-1098 3200);
DISPLAY 0.872340 (-1098 3200);
PAINT GREEN (-1098 3200);
DISPLAY INVISIBLE (-1098 3200);
FORCEADD TAP..1
R 2
(-1100 150);
FORCEPROP 3 LASTPIN (-1050 150) SIG_NAME M_A_CPU1_CLK_DP<0>
J 0
(-1040 160);
DISPLAY 0.659574 (-1040 160);
PAINT MONO (-1040 160);
DISPLAY INVISIBLE (-1040 160);
FORCEPROP 1 LASTPIN (-1050 150) BN 0
J 2
(-1038 158);
DISPLAY 0.680851 (-1038 158);
PAINT GREEN (-1038 158);
FORCEPROP 2 LAST CDS_LIB standard
J 0
(-1100 150);
DISPLAY INVISIBLE (-1100 150);
FORCEPROP 1 LAST BODY_TYPE PLUMBING
J 2
(-1100 200);
DISPLAY 0.872340 (-1100 200);
PAINT GREEN (-1100 200);
DISPLAY INVISIBLE (-1100 200);
FORCEPROP 1 LAST HDL_TAP TRUE
J 2
(-1425 25);
DISPLAY 0.872340 (-1425 25);
DISPLAY INVISIBLE (-1425 25);
FORCEPROP 1 LAST PATH I7
J 2
(-1098 150);
DISPLAY 0.872340 (-1098 150);
PAINT GREEN (-1098 150);
DISPLAY INVISIBLE (-1098 150);
FORCEADD TAP..1
R 2
(-1100 3250);
FORCEPROP 3 LASTPIN (-1050 3250) SIG_NAME M_A_CPU1_SA_DQ<11>
J 0
(-1040 3260);
DISPLAY 0.659574 (-1040 3260);
PAINT MONO (-1040 3260);
DISPLAY INVISIBLE (-1040 3260);
FORCEPROP 1 LASTPIN (-1050 3250) BN 11
J 2
(-1038 3258);
DISPLAY 0.680851 (-1038 3258);
PAINT GREEN (-1038 3258);
FORCEPROP 2 LAST CDS_LIB standard
J 0
(-1100 3250);
DISPLAY INVISIBLE (-1100 3250);
FORCEPROP 1 LAST BODY_TYPE PLUMBING
J 2
(-1100 3300);
DISPLAY 0.872340 (-1100 3300);
PAINT GREEN (-1100 3300);
DISPLAY INVISIBLE (-1100 3300);
FORCEPROP 1 LAST HDL_TAP TRUE
J 2
(-1425 3125);
DISPLAY 0.872340 (-1425 3125);
DISPLAY INVISIBLE (-1425 3125);
FORCEPROP 1 LAST PATH I70
J 2
(-1098 3250);
DISPLAY 0.872340 (-1098 3250);
PAINT GREEN (-1098 3250);
DISPLAY INVISIBLE (-1098 3250);
FORCEADD TAP..1
R 2
(-1100 3350);
FORCEPROP 3 LASTPIN (-1050 3350) SIG_NAME M_A_CPU1_SA_DQ<13>
J 0
(-1040 3360);
DISPLAY 0.659574 (-1040 3360);
PAINT MONO (-1040 3360);
DISPLAY INVISIBLE (-1040 3360);
FORCEPROP 1 LASTPIN (-1050 3350) BN 13
J 2
(-1038 3358);
DISPLAY 0.680851 (-1038 3358);
PAINT GREEN (-1038 3358);
FORCEPROP 2 LAST CDS_LIB standard
J 0
(-1100 3350);
DISPLAY INVISIBLE (-1100 3350);
FORCEPROP 1 LAST BODY_TYPE PLUMBING
J 2
(-1100 3400);
DISPLAY 0.872340 (-1100 3400);
PAINT GREEN (-1100 3400);
DISPLAY INVISIBLE (-1100 3400);
FORCEPROP 1 LAST HDL_TAP TRUE
J 2
(-1425 3225);
DISPLAY 0.872340 (-1425 3225);
DISPLAY INVISIBLE (-1425 3225);
FORCEPROP 1 LAST PATH I71
J 2
(-1098 3350);
DISPLAY 0.872340 (-1098 3350);
PAINT GREEN (-1098 3350);
DISPLAY INVISIBLE (-1098 3350);
FORCEADD TAP..1
R 2
(-1100 3300);
FORCEPROP 3 LASTPIN (-1050 3300) SIG_NAME M_A_CPU1_SA_DQ<12>
J 0
(-1040 3310);
DISPLAY 0.659574 (-1040 3310);
PAINT MONO (-1040 3310);
DISPLAY INVISIBLE (-1040 3310);
FORCEPROP 1 LASTPIN (-1050 3300) BN 12
J 2
(-1038 3308);
DISPLAY 0.680851 (-1038 3308);
PAINT GREEN (-1038 3308);
FORCEPROP 2 LAST CDS_LIB standard
J 0
(-1100 3300);
DISPLAY INVISIBLE (-1100 3300);
FORCEPROP 1 LAST BODY_TYPE PLUMBING
J 2
(-1100 3350);
DISPLAY 0.872340 (-1100 3350);
PAINT GREEN (-1100 3350);
DISPLAY INVISIBLE (-1100 3350);
FORCEPROP 1 LAST HDL_TAP TRUE
J 2
(-1425 3175);
DISPLAY 0.872340 (-1425 3175);
DISPLAY INVISIBLE (-1425 3175);
FORCEPROP 1 LAST PATH I72
J 2
(-1098 3300);
DISPLAY 0.872340 (-1098 3300);
PAINT GREEN (-1098 3300);
DISPLAY INVISIBLE (-1098 3300);
FORCEADD TAP..1
R 2
(-1100 3400);
FORCEPROP 3 LASTPIN (-1050 3400) SIG_NAME M_A_CPU1_SA_DQ<14>
J 0
(-1040 3410);
DISPLAY 0.659574 (-1040 3410);
PAINT MONO (-1040 3410);
DISPLAY INVISIBLE (-1040 3410);
FORCEPROP 1 LASTPIN (-1050 3400) BN 14
J 2
(-1038 3408);
DISPLAY 0.680851 (-1038 3408);
PAINT GREEN (-1038 3408);
FORCEPROP 2 LAST CDS_LIB standard
J 0
(-1100 3400);
DISPLAY INVISIBLE (-1100 3400);
FORCEPROP 1 LAST BODY_TYPE PLUMBING
J 2
(-1100 3450);
DISPLAY 0.872340 (-1100 3450);
PAINT GREEN (-1100 3450);
DISPLAY INVISIBLE (-1100 3450);
FORCEPROP 1 LAST HDL_TAP TRUE
J 2
(-1425 3275);
DISPLAY 0.872340 (-1425 3275);
DISPLAY INVISIBLE (-1425 3275);
FORCEPROP 1 LAST PATH I73
J 2
(-1098 3400);
DISPLAY 0.872340 (-1098 3400);
PAINT GREEN (-1098 3400);
DISPLAY INVISIBLE (-1098 3400);
FORCEADD TAP..1
R 2
(-1100 3450);
FORCEPROP 3 LASTPIN (-1050 3450) SIG_NAME M_A_CPU1_SA_DQ<15>
J 0
(-1040 3460);
DISPLAY 0.659574 (-1040 3460);
PAINT MONO (-1040 3460);
DISPLAY INVISIBLE (-1040 3460);
FORCEPROP 1 LASTPIN (-1050 3450) BN 15
J 2
(-1038 3458);
DISPLAY 0.680851 (-1038 3458);
PAINT GREEN (-1038 3458);
FORCEPROP 2 LAST CDS_LIB standard
J 0
(-1100 3450);
DISPLAY INVISIBLE (-1100 3450);
FORCEPROP 1 LAST BODY_TYPE PLUMBING
J 2
(-1100 3500);
DISPLAY 0.872340 (-1100 3500);
PAINT GREEN (-1100 3500);
DISPLAY INVISIBLE (-1100 3500);
FORCEPROP 1 LAST HDL_TAP TRUE
J 2
(-1425 3325);
DISPLAY 0.872340 (-1425 3325);
DISPLAY INVISIBLE (-1425 3325);
FORCEPROP 1 LAST PATH I74
J 2
(-1098 3450);
DISPLAY 0.872340 (-1098 3450);
PAINT GREEN (-1098 3450);
DISPLAY INVISIBLE (-1098 3450);
FORCEADD TAP..1
R 2
(-1100 3550);
FORCEPROP 3 LASTPIN (-1050 3550) SIG_NAME M_A_CPU1_SA_DQ<17>
J 0
(-1040 3560);
DISPLAY 0.659574 (-1040 3560);
PAINT MONO (-1040 3560);
DISPLAY INVISIBLE (-1040 3560);
FORCEPROP 1 LASTPIN (-1050 3550) BN 17
J 2
(-1038 3558);
DISPLAY 0.680851 (-1038 3558);
PAINT GREEN (-1038 3558);
FORCEPROP 2 LAST CDS_LIB standard
J 0
(-1100 3550);
DISPLAY INVISIBLE (-1100 3550);
FORCEPROP 1 LAST BODY_TYPE PLUMBING
J 2
(-1100 3600);
DISPLAY 0.872340 (-1100 3600);
PAINT GREEN (-1100 3600);
DISPLAY INVISIBLE (-1100 3600);
FORCEPROP 1 LAST HDL_TAP TRUE
J 2
(-1425 3425);
DISPLAY 0.872340 (-1425 3425);
DISPLAY INVISIBLE (-1425 3425);
FORCEPROP 1 LAST PATH I75
J 2
(-1098 3550);
DISPLAY 0.872340 (-1098 3550);
PAINT GREEN (-1098 3550);
DISPLAY INVISIBLE (-1098 3550);
FORCEADD TAP..1
R 2
(-1100 3600);
FORCEPROP 3 LASTPIN (-1050 3600) SIG_NAME M_A_CPU1_SA_DQ<18>
J 0
(-1040 3610);
DISPLAY 0.659574 (-1040 3610);
PAINT MONO (-1040 3610);
DISPLAY INVISIBLE (-1040 3610);
FORCEPROP 1 LASTPIN (-1050 3600) BN 18
J 2
(-1038 3608);
DISPLAY 0.680851 (-1038 3608);
PAINT GREEN (-1038 3608);
FORCEPROP 2 LAST CDS_LIB standard
J 0
(-1100 3600);
DISPLAY INVISIBLE (-1100 3600);
FORCEPROP 1 LAST BODY_TYPE PLUMBING
J 2
(-1100 3650);
DISPLAY 0.872340 (-1100 3650);
PAINT GREEN (-1100 3650);
DISPLAY INVISIBLE (-1100 3650);
FORCEPROP 1 LAST HDL_TAP TRUE
J 2
(-1425 3475);
DISPLAY 0.872340 (-1425 3475);
DISPLAY INVISIBLE (-1425 3475);
FORCEPROP 1 LAST PATH I76
J 2
(-1098 3600);
DISPLAY 0.872340 (-1098 3600);
PAINT GREEN (-1098 3600);
DISPLAY INVISIBLE (-1098 3600);
FORCEADD TAP..1
R 2
(-1100 3500);
FORCEPROP 3 LASTPIN (-1050 3500) SIG_NAME M_A_CPU1_SA_DQ<16>
J 0
(-1040 3510);
DISPLAY 0.659574 (-1040 3510);
PAINT MONO (-1040 3510);
DISPLAY INVISIBLE (-1040 3510);
FORCEPROP 1 LASTPIN (-1050 3500) BN 16
J 2
(-1038 3508);
DISPLAY 0.680851 (-1038 3508);
PAINT GREEN (-1038 3508);
FORCEPROP 2 LAST CDS_LIB standard
J 0
(-1100 3500);
DISPLAY INVISIBLE (-1100 3500);
FORCEPROP 1 LAST BODY_TYPE PLUMBING
J 2
(-1100 3550);
DISPLAY 0.872340 (-1100 3550);
PAINT GREEN (-1100 3550);
DISPLAY INVISIBLE (-1100 3550);
FORCEPROP 1 LAST HDL_TAP TRUE
J 2
(-1425 3375);
DISPLAY 0.872340 (-1425 3375);
DISPLAY INVISIBLE (-1425 3375);
FORCEPROP 1 LAST PATH I77
J 2
(-1098 3500);
DISPLAY 0.872340 (-1098 3500);
PAINT GREEN (-1098 3500);
DISPLAY INVISIBLE (-1098 3500);
FORCEADD TAP..1
R 2
(-1100 3650);
FORCEPROP 3 LASTPIN (-1050 3650) SIG_NAME M_A_CPU1_SA_DQ<19>
J 0
(-1040 3660);
DISPLAY 0.659574 (-1040 3660);
PAINT MONO (-1040 3660);
DISPLAY INVISIBLE (-1040 3660);
FORCEPROP 1 LASTPIN (-1050 3650) BN 19
J 2
(-1038 3658);
DISPLAY 0.680851 (-1038 3658);
PAINT GREEN (-1038 3658);
FORCEPROP 2 LAST CDS_LIB standard
J 0
(-1100 3650);
DISPLAY INVISIBLE (-1100 3650);
FORCEPROP 1 LAST BODY_TYPE PLUMBING
J 2
(-1100 3700);
DISPLAY 0.872340 (-1100 3700);
PAINT GREEN (-1100 3700);
DISPLAY INVISIBLE (-1100 3700);
FORCEPROP 1 LAST HDL_TAP TRUE
J 2
(-1425 3525);
DISPLAY 0.872340 (-1425 3525);
DISPLAY INVISIBLE (-1425 3525);
FORCEPROP 1 LAST PATH I78
J 2
(-1098 3650);
DISPLAY 0.872340 (-1098 3650);
PAINT GREEN (-1098 3650);
DISPLAY INVISIBLE (-1098 3650);
FORCEADD TAP..1
R 2
(-1100 3700);
FORCEPROP 3 LASTPIN (-1050 3700) SIG_NAME M_A_CPU1_SA_DQ<20>
J 0
(-1040 3710);
DISPLAY 0.659574 (-1040 3710);
PAINT MONO (-1040 3710);
DISPLAY INVISIBLE (-1040 3710);
FORCEPROP 1 LASTPIN (-1050 3700) BN 20
J 2
(-1038 3708);
DISPLAY 0.680851 (-1038 3708);
PAINT GREEN (-1038 3708);
FORCEPROP 2 LAST CDS_LIB standard
J 0
(-1100 3700);
DISPLAY INVISIBLE (-1100 3700);
FORCEPROP 1 LAST BODY_TYPE PLUMBING
J 2
(-1100 3750);
DISPLAY 0.872340 (-1100 3750);
PAINT GREEN (-1100 3750);
DISPLAY INVISIBLE (-1100 3750);
FORCEPROP 1 LAST HDL_TAP TRUE
J 2
(-1425 3575);
DISPLAY 0.872340 (-1425 3575);
DISPLAY INVISIBLE (-1425 3575);
FORCEPROP 1 LAST PATH I79
J 2
(-1098 3700);
DISPLAY 0.872340 (-1098 3700);
PAINT GREEN (-1098 3700);
DISPLAY INVISIBLE (-1098 3700);
FORCEADD TAP..1
R 2
(-1100 100);
FORCEPROP 3 LASTPIN (-1050 100) SIG_NAME M_A_CPU1_CLK_DN<1>
J 0
(-1040 110);
DISPLAY 0.659574 (-1040 110);
PAINT MONO (-1040 110);
DISPLAY INVISIBLE (-1040 110);
FORCEPROP 1 LASTPIN (-1050 100) BN 1
J 2
(-1038 108);
DISPLAY 0.680851 (-1038 108);
PAINT GREEN (-1038 108);
FORCEPROP 2 LAST CDS_LIB standard
J 0
(-1100 100);
DISPLAY INVISIBLE (-1100 100);
FORCEPROP 1 LAST BODY_TYPE PLUMBING
J 2
(-1100 150);
DISPLAY 0.872340 (-1100 150);
PAINT GREEN (-1100 150);
DISPLAY INVISIBLE (-1100 150);
FORCEPROP 1 LAST HDL_TAP TRUE
J 2
(-1425 -25);
DISPLAY 0.872340 (-1425 -25);
DISPLAY INVISIBLE (-1425 -25);
FORCEPROP 1 LAST PATH I8
J 2
(-1098 100);
DISPLAY 0.872340 (-1098 100);
PAINT GREEN (-1098 100);
DISPLAY INVISIBLE (-1098 100);
FORCEADD TAP..1
R 2
(-1100 3750);
FORCEPROP 3 LASTPIN (-1050 3750) SIG_NAME M_A_CPU1_SA_DQ<21>
J 0
(-1040 3760);
DISPLAY 0.659574 (-1040 3760);
PAINT MONO (-1040 3760);
DISPLAY INVISIBLE (-1040 3760);
FORCEPROP 1 LASTPIN (-1050 3750) BN 21
J 2
(-1038 3758);
DISPLAY 0.680851 (-1038 3758);
PAINT GREEN (-1038 3758);
FORCEPROP 2 LAST CDS_LIB standard
J 0
(-1100 3750);
DISPLAY INVISIBLE (-1100 3750);
FORCEPROP 1 LAST BODY_TYPE PLUMBING
J 2
(-1100 3800);
DISPLAY 0.872340 (-1100 3800);
PAINT GREEN (-1100 3800);
DISPLAY INVISIBLE (-1100 3800);
FORCEPROP 1 LAST HDL_TAP TRUE
J 2
(-1425 3625);
DISPLAY 0.872340 (-1425 3625);
DISPLAY INVISIBLE (-1425 3625);
FORCEPROP 1 LAST PATH I80
J 2
(-1098 3750);
DISPLAY 0.872340 (-1098 3750);
PAINT GREEN (-1098 3750);
DISPLAY INVISIBLE (-1098 3750);
FORCEADD TAP..1
R 2
(-1100 3850);
FORCEPROP 3 LASTPIN (-1050 3850) SIG_NAME M_A_CPU1_SA_DQ<23>
J 0
(-1040 3860);
DISPLAY 0.659574 (-1040 3860);
PAINT MONO (-1040 3860);
DISPLAY INVISIBLE (-1040 3860);
FORCEPROP 1 LASTPIN (-1050 3850) BN 23
J 2
(-1038 3858);
DISPLAY 0.680851 (-1038 3858);
PAINT GREEN (-1038 3858);
FORCEPROP 2 LAST CDS_LIB standard
J 0
(-1100 3850);
DISPLAY INVISIBLE (-1100 3850);
FORCEPROP 1 LAST BODY_TYPE PLUMBING
J 2
(-1100 3900);
DISPLAY 0.872340 (-1100 3900);
PAINT GREEN (-1100 3900);
DISPLAY INVISIBLE (-1100 3900);
FORCEPROP 1 LAST HDL_TAP TRUE
J 2
(-1425 3725);
DISPLAY 0.872340 (-1425 3725);
DISPLAY INVISIBLE (-1425 3725);
FORCEPROP 1 LAST PATH I81
J 2
(-1098 3850);
DISPLAY 0.872340 (-1098 3850);
PAINT GREEN (-1098 3850);
DISPLAY INVISIBLE (-1098 3850);
FORCEADD TAP..1
R 2
(-1100 3800);
FORCEPROP 3 LASTPIN (-1050 3800) SIG_NAME M_A_CPU1_SA_DQ<22>
J 0
(-1040 3810);
DISPLAY 0.659574 (-1040 3810);
PAINT MONO (-1040 3810);
DISPLAY INVISIBLE (-1040 3810);
FORCEPROP 1 LASTPIN (-1050 3800) BN 22
J 2
(-1038 3808);
DISPLAY 0.680851 (-1038 3808);
PAINT GREEN (-1038 3808);
FORCEPROP 2 LAST CDS_LIB standard
J 0
(-1100 3800);
DISPLAY INVISIBLE (-1100 3800);
FORCEPROP 1 LAST BODY_TYPE PLUMBING
J 2
(-1100 3850);
DISPLAY 0.872340 (-1100 3850);
PAINT GREEN (-1100 3850);
DISPLAY INVISIBLE (-1100 3850);
FORCEPROP 1 LAST HDL_TAP TRUE
J 2
(-1425 3675);
DISPLAY 0.872340 (-1425 3675);
DISPLAY INVISIBLE (-1425 3675);
FORCEPROP 1 LAST PATH I82
J 2
(-1098 3800);
DISPLAY 0.872340 (-1098 3800);
PAINT GREEN (-1098 3800);
DISPLAY INVISIBLE (-1098 3800);
FORCEADD TAP..1
R 2
(-1100 3900);
FORCEPROP 3 LASTPIN (-1050 3900) SIG_NAME M_A_CPU1_SA_DQ<24>
J 0
(-1040 3910);
DISPLAY 0.659574 (-1040 3910);
PAINT MONO (-1040 3910);
DISPLAY INVISIBLE (-1040 3910);
FORCEPROP 1 LASTPIN (-1050 3900) BN 24
J 2
(-1038 3908);
DISPLAY 0.680851 (-1038 3908);
PAINT GREEN (-1038 3908);
FORCEPROP 2 LAST CDS_LIB standard
J 0
(-1100 3900);
DISPLAY INVISIBLE (-1100 3900);
FORCEPROP 1 LAST BODY_TYPE PLUMBING
J 2
(-1100 3950);
DISPLAY 0.872340 (-1100 3950);
PAINT GREEN (-1100 3950);
DISPLAY INVISIBLE (-1100 3950);
FORCEPROP 1 LAST HDL_TAP TRUE
J 2
(-1425 3775);
DISPLAY 0.872340 (-1425 3775);
DISPLAY INVISIBLE (-1425 3775);
FORCEPROP 1 LAST PATH I83
J 2
(-1098 3900);
DISPLAY 0.872340 (-1098 3900);
PAINT GREEN (-1098 3900);
DISPLAY INVISIBLE (-1098 3900);
FORCEADD TAP..1
R 2
(-1100 3950);
FORCEPROP 3 LASTPIN (-1050 3950) SIG_NAME M_A_CPU1_SA_DQ<25>
J 0
(-1040 3960);
DISPLAY 0.659574 (-1040 3960);
PAINT MONO (-1040 3960);
DISPLAY INVISIBLE (-1040 3960);
FORCEPROP 1 LASTPIN (-1050 3950) BN 25
J 2
(-1038 3958);
DISPLAY 0.680851 (-1038 3958);
PAINT GREEN (-1038 3958);
FORCEPROP 2 LAST CDS_LIB standard
J 0
(-1100 3950);
DISPLAY INVISIBLE (-1100 3950);
FORCEPROP 1 LAST BODY_TYPE PLUMBING
J 2
(-1100 4000);
DISPLAY 0.872340 (-1100 4000);
PAINT GREEN (-1100 4000);
DISPLAY INVISIBLE (-1100 4000);
FORCEPROP 1 LAST HDL_TAP TRUE
J 2
(-1425 3825);
DISPLAY 0.872340 (-1425 3825);
DISPLAY INVISIBLE (-1425 3825);
FORCEPROP 1 LAST PATH I84
J 2
(-1098 3950);
DISPLAY 0.872340 (-1098 3950);
PAINT GREEN (-1098 3950);
DISPLAY INVISIBLE (-1098 3950);
FORCEADD TAP..1
R 2
(-1100 4000);
FORCEPROP 3 LASTPIN (-1050 4000) SIG_NAME M_A_CPU1_SA_DQ<26>
J 0
(-1040 4010);
DISPLAY 0.659574 (-1040 4010);
PAINT MONO (-1040 4010);
DISPLAY INVISIBLE (-1040 4010);
FORCEPROP 1 LASTPIN (-1050 4000) BN 26
J 2
(-1038 4008);
DISPLAY 0.680851 (-1038 4008);
PAINT GREEN (-1038 4008);
FORCEPROP 2 LAST CDS_LIB standard
J 0
(-1100 4000);
DISPLAY INVISIBLE (-1100 4000);
FORCEPROP 1 LAST BODY_TYPE PLUMBING
J 2
(-1100 4050);
DISPLAY 0.872340 (-1100 4050);
PAINT GREEN (-1100 4050);
DISPLAY INVISIBLE (-1100 4050);
FORCEPROP 1 LAST HDL_TAP TRUE
J 2
(-1425 3875);
DISPLAY 0.872340 (-1425 3875);
DISPLAY INVISIBLE (-1425 3875);
FORCEPROP 1 LAST PATH I85
J 2
(-1098 4000);
DISPLAY 0.872340 (-1098 4000);
PAINT GREEN (-1098 4000);
DISPLAY INVISIBLE (-1098 4000);
FORCEADD TAP..1
R 2
(-1100 4050);
FORCEPROP 3 LASTPIN (-1050 4050) SIG_NAME M_A_CPU1_SA_DQ<27>
J 0
(-1040 4060);
DISPLAY 0.659574 (-1040 4060);
PAINT MONO (-1040 4060);
DISPLAY INVISIBLE (-1040 4060);
FORCEPROP 1 LASTPIN (-1050 4050) BN 27
J 2
(-1038 4058);
DISPLAY 0.680851 (-1038 4058);
PAINT GREEN (-1038 4058);
FORCEPROP 2 LAST CDS_LIB standard
J 0
(-1100 4050);
DISPLAY INVISIBLE (-1100 4050);
FORCEPROP 1 LAST BODY_TYPE PLUMBING
J 2
(-1100 4100);
DISPLAY 0.872340 (-1100 4100);
PAINT GREEN (-1100 4100);
DISPLAY INVISIBLE (-1100 4100);
FORCEPROP 1 LAST HDL_TAP TRUE
J 2
(-1425 3925);
DISPLAY 0.872340 (-1425 3925);
DISPLAY INVISIBLE (-1425 3925);
FORCEPROP 1 LAST PATH I86
J 2
(-1098 4050);
DISPLAY 0.872340 (-1098 4050);
PAINT GREEN (-1098 4050);
DISPLAY INVISIBLE (-1098 4050);
FORCEADD TAP..1
R 2
(-1100 4100);
FORCEPROP 3 LASTPIN (-1050 4100) SIG_NAME M_A_CPU1_SA_DQ<28>
J 0
(-1040 4110);
DISPLAY 0.659574 (-1040 4110);
PAINT MONO (-1040 4110);
DISPLAY INVISIBLE (-1040 4110);
FORCEPROP 1 LASTPIN (-1050 4100) BN 28
J 2
(-1038 4108);
DISPLAY 0.680851 (-1038 4108);
PAINT GREEN (-1038 4108);
FORCEPROP 2 LAST CDS_LIB standard
J 0
(-1100 4100);
DISPLAY INVISIBLE (-1100 4100);
FORCEPROP 1 LAST BODY_TYPE PLUMBING
J 2
(-1100 4150);
DISPLAY 0.872340 (-1100 4150);
PAINT GREEN (-1100 4150);
DISPLAY INVISIBLE (-1100 4150);
FORCEPROP 1 LAST HDL_TAP TRUE
J 2
(-1425 3975);
DISPLAY 0.872340 (-1425 3975);
DISPLAY INVISIBLE (-1425 3975);
FORCEPROP 1 LAST PATH I87
J 2
(-1098 4100);
DISPLAY 0.872340 (-1098 4100);
PAINT GREEN (-1098 4100);
DISPLAY INVISIBLE (-1098 4100);
FORCEADD OFFPAGE..3
R 2
(-2125 4275);
FORCEPROP 2 LAST $XR1 99 
J 0
(-2494 4275);
DISPLAY 0.638298 (-2494 4275);
PAINT MONO (-2494 4275);
FORCEPROP 2 LAST $XR0 98 
J 0
(-2404 4275);
DISPLAY 0.638298 (-2404 4275);
PAINT MONO (-2404 4275);
FORCEPROP 2 LAST CDS_LIB standard
J 0
(-2125 4275);
DISPLAY INVISIBLE (-2125 4275);
FORCEPROP 1 LAST OFFPAGE TRUE
J 2
(-2450 4150);
DISPLAY 0.872340 (-2450 4150);
DISPLAY INVISIBLE (-2450 4150);
FORCEPROP 1 LAST COMMENT_BODY TRUE
J 2
(-2075 4175);
DISPLAY 0.872340 (-2075 4175);
PAINT GREEN (-2075 4175);
DISPLAY INVISIBLE (-2075 4175);
FORCEPROP 2 LAST PATH I88
J 0
(-2075 4350);
DISPLAY 1.021277 (-2075 4350);
DISPLAY INVISIBLE (-2075 4350);
FORCEADD TAP..1
R 2
(-1100 4250);
FORCEPROP 3 LASTPIN (-1050 4250) SIG_NAME M_A_CPU1_SA_DQ<31>
J 0
(-1040 4260);
DISPLAY 0.659574 (-1040 4260);
PAINT MONO (-1040 4260);
DISPLAY INVISIBLE (-1040 4260);
FORCEPROP 1 LASTPIN (-1050 4250) BN 31
J 2
(-1038 4258);
DISPLAY 0.680851 (-1038 4258);
PAINT GREEN (-1038 4258);
FORCEPROP 2 LAST CDS_LIB standard
J 0
(-1100 4250);
DISPLAY INVISIBLE (-1100 4250);
FORCEPROP 1 LAST BODY_TYPE PLUMBING
J 2
(-1100 4300);
DISPLAY 0.872340 (-1100 4300);
PAINT GREEN (-1100 4300);
DISPLAY INVISIBLE (-1100 4300);
FORCEPROP 1 LAST HDL_TAP TRUE
J 2
(-1425 4125);
DISPLAY 0.872340 (-1425 4125);
DISPLAY INVISIBLE (-1425 4125);
FORCEPROP 1 LAST PATH I89
J 2
(-1098 4250);
DISPLAY 0.872340 (-1098 4250);
PAINT GREEN (-1098 4250);
DISPLAY INVISIBLE (-1098 4250);
FORCEADD TAP..1
R 2
(-1100 300);
FORCEPROP 3 LASTPIN (-1050 300) SIG_NAME M_A_CPU1_SB_CB<0>
J 0
(-1040 310);
DISPLAY 0.659574 (-1040 310);
PAINT MONO (-1040 310);
DISPLAY INVISIBLE (-1040 310);
FORCEPROP 1 LASTPIN (-1050 300) BN 0
J 2
(-1038 308);
DISPLAY 0.680851 (-1038 308);
PAINT GREEN (-1038 308);
FORCEPROP 2 LAST CDS_LIB standard
J 0
(-1100 300);
DISPLAY INVISIBLE (-1100 300);
FORCEPROP 1 LAST BODY_TYPE PLUMBING
J 2
(-1100 350);
DISPLAY 0.872340 (-1100 350);
PAINT GREEN (-1100 350);
DISPLAY INVISIBLE (-1100 350);
FORCEPROP 1 LAST HDL_TAP TRUE
J 2
(-1425 175);
DISPLAY 0.872340 (-1425 175);
DISPLAY INVISIBLE (-1425 175);
FORCEPROP 1 LAST PATH I9
J 2
(-1098 300);
DISPLAY 0.872340 (-1098 300);
PAINT GREEN (-1098 300);
DISPLAY INVISIBLE (-1098 300);
FORCEADD TAP..1
R 2
(-1100 4200);
FORCEPROP 3 LASTPIN (-1050 4200) SIG_NAME M_A_CPU1_SA_DQ<30>
J 0
(-1040 4210);
DISPLAY 0.659574 (-1040 4210);
PAINT MONO (-1040 4210);
DISPLAY INVISIBLE (-1040 4210);
FORCEPROP 1 LASTPIN (-1050 4200) BN 30
J 2
(-1038 4208);
DISPLAY 0.680851 (-1038 4208);
PAINT GREEN (-1038 4208);
FORCEPROP 2 LAST CDS_LIB standard
J 0
(-1100 4200);
DISPLAY INVISIBLE (-1100 4200);
FORCEPROP 1 LAST BODY_TYPE PLUMBING
J 2
(-1100 4250);
DISPLAY 0.872340 (-1100 4250);
PAINT GREEN (-1100 4250);
DISPLAY INVISIBLE (-1100 4250);
FORCEPROP 1 LAST HDL_TAP TRUE
J 2
(-1425 4075);
DISPLAY 0.872340 (-1425 4075);
DISPLAY INVISIBLE (-1425 4075);
FORCEPROP 1 LAST PATH I90
J 2
(-1098 4200);
DISPLAY 0.872340 (-1098 4200);
PAINT GREEN (-1098 4200);
DISPLAY INVISIBLE (-1098 4200);
FORCEADD TAP..1
R 2
(-1100 4150);
FORCEPROP 3 LASTPIN (-1050 4150) SIG_NAME M_A_CPU1_SA_DQ<29>
J 0
(-1040 4160);
DISPLAY 0.659574 (-1040 4160);
PAINT MONO (-1040 4160);
DISPLAY INVISIBLE (-1040 4160);
FORCEPROP 1 LASTPIN (-1050 4150) BN 29
J 2
(-1038 4158);
DISPLAY 0.680851 (-1038 4158);
PAINT GREEN (-1038 4158);
FORCEPROP 2 LAST CDS_LIB standard
J 0
(-1100 4150);
DISPLAY INVISIBLE (-1100 4150);
FORCEPROP 1 LAST BODY_TYPE PLUMBING
J 2
(-1100 4200);
DISPLAY 0.872340 (-1100 4200);
PAINT GREEN (-1100 4200);
DISPLAY INVISIBLE (-1100 4200);
FORCEPROP 1 LAST HDL_TAP TRUE
J 2
(-1425 4025);
DISPLAY 0.872340 (-1425 4025);
DISPLAY INVISIBLE (-1425 4025);
FORCEPROP 1 LAST PATH I91
J 2
(-1098 4150);
DISPLAY 0.872340 (-1098 4150);
PAINT GREEN (-1098 4150);
DISPLAY INVISIBLE (-1098 4150);
FORCEADD OFFPAGE..4
(3425 50);
FORCEPROP 2 LAST $XR1 99 
J 0
(3701 50);
DISPLAY 0.638298 (3701 50);
PAINT MONO (3701 50);
FORCEPROP 2 LAST $XR0 98 
J 0
(3611 50);
DISPLAY 0.638298 (3611 50);
PAINT MONO (3611 50);
FORCEPROP 2 LAST CDS_LIB standard
J 0
(3425 50);
PAINT MONO (3425 50);
DISPLAY INVISIBLE (3425 50);
FORCEPROP 1 LAST OFFPAGE TRUE
J 0
(3750 -75);
DISPLAY 1.170213 (3750 -75);
PAINT GREEN (3750 -75);
DISPLAY INVISIBLE (3750 -75);
FORCEPROP 1 LAST COMMENT_BODY TRUE
J 0
(3400 -50);
DISPLAY 1.170213 (3400 -50);
PAINT GREEN (3400 -50);
DISPLAY INVISIBLE (3400 -50);
FORCEPROP 2 LAST PATH I92
J 0
(3600 125);
DISPLAY 1.021277 (3600 125);
DISPLAY INVISIBLE (3600 125);
FORCEADD TAP..1
(2325 550);
FORCEPROP 3 LASTPIN (2275 550) SIG_NAME M_A_CPU1_SB_CS_N<1>
J 0
(2285 560);
DISPLAY 0.659574 (2285 560);
PAINT MONO (2285 560);
DISPLAY INVISIBLE (2285 560);
FORCEPROP 1 LASTPIN (2275 550) BN 1
J 0
(2263 558);
DISPLAY 0.680851 (2263 558);
PAINT GREEN (2263 558);
FORCEPROP 2 LAST CDS_LIB standard
J 0
(2325 550);
DISPLAY INVISIBLE (2325 550);
FORCEPROP 1 LAST BODY_TYPE PLUMBING
J 0
(2325 600);
DISPLAY 0.872340 (2325 600);
PAINT GREEN (2325 600);
DISPLAY INVISIBLE (2325 600);
FORCEPROP 1 LAST HDL_TAP TRUE
J 0
(2650 425);
DISPLAY 0.872340 (2650 425);
DISPLAY INVISIBLE (2650 425);
FORCEPROP 1 LAST PATH I93
J 0
(2323 550);
DISPLAY 0.872340 (2323 550);
PAINT GREEN (2323 550);
DISPLAY INVISIBLE (2323 550);
FORCEADD TAP..1
(2325 500);
FORCEPROP 3 LASTPIN (2275 500) SIG_NAME M_A_CPU1_SB_CS_N<0>
J 0
(2285 510);
DISPLAY 0.659574 (2285 510);
PAINT MONO (2285 510);
DISPLAY INVISIBLE (2285 510);
FORCEPROP 1 LASTPIN (2275 500) BN 0
J 0
(2263 508);
DISPLAY 0.680851 (2263 508);
PAINT GREEN (2263 508);
FORCEPROP 2 LAST CDS_LIB standard
J 0
(2325 500);
DISPLAY INVISIBLE (2325 500);
FORCEPROP 1 LAST BODY_TYPE PLUMBING
J 0
(2325 550);
DISPLAY 0.872340 (2325 550);
PAINT GREEN (2325 550);
DISPLAY INVISIBLE (2325 550);
FORCEPROP 1 LAST HDL_TAP TRUE
J 0
(2650 375);
DISPLAY 0.872340 (2650 375);
DISPLAY INVISIBLE (2650 375);
FORCEPROP 1 LAST PATH I94
J 0
(2323 500);
DISPLAY 0.872340 (2323 500);
PAINT GREEN (2323 500);
DISPLAY INVISIBLE (2323 500);
FORCEADD TAP..1
(2325 650);
FORCEPROP 3 LASTPIN (2275 650) SIG_NAME M_A_CPU1_SB_CS_N<3>
J 0
(2285 660);
DISPLAY 0.659574 (2285 660);
PAINT MONO (2285 660);
DISPLAY INVISIBLE (2285 660);
FORCEPROP 1 LASTPIN (2275 650) BN 3
J 0
(2263 658);
DISPLAY 0.680851 (2263 658);
PAINT GREEN (2263 658);
FORCEPROP 2 LAST CDS_LIB standard
J 0
(2325 650);
DISPLAY INVISIBLE (2325 650);
FORCEPROP 1 LAST BODY_TYPE PLUMBING
J 0
(2325 700);
DISPLAY 0.872340 (2325 700);
PAINT GREEN (2325 700);
DISPLAY INVISIBLE (2325 700);
FORCEPROP 1 LAST HDL_TAP TRUE
J 0
(2650 525);
DISPLAY 0.872340 (2650 525);
DISPLAY INVISIBLE (2650 525);
FORCEPROP 1 LAST PATH I95
J 0
(2323 650);
DISPLAY 0.872340 (2323 650);
PAINT GREEN (2323 650);
DISPLAY INVISIBLE (2323 650);
FORCEADD TAP..1
(2325 600);
FORCEPROP 3 LASTPIN (2275 600) SIG_NAME M_A_CPU1_SB_CS_N<2>
J 0
(2285 610);
DISPLAY 0.659574 (2285 610);
PAINT MONO (2285 610);
DISPLAY INVISIBLE (2285 610);
FORCEPROP 1 LASTPIN (2275 600) BN 2
J 0
(2263 608);
DISPLAY 0.680851 (2263 608);
PAINT GREEN (2263 608);
FORCEPROP 2 LAST CDS_LIB standard
J 0
(2325 600);
DISPLAY INVISIBLE (2325 600);
FORCEPROP 1 LAST BODY_TYPE PLUMBING
J 0
(2325 650);
DISPLAY 0.872340 (2325 650);
PAINT GREEN (2325 650);
DISPLAY INVISIBLE (2325 650);
FORCEPROP 1 LAST HDL_TAP TRUE
J 0
(2650 475);
DISPLAY 0.872340 (2650 475);
DISPLAY INVISIBLE (2650 475);
FORCEPROP 1 LAST PATH I96
J 0
(2323 600);
DISPLAY 0.872340 (2323 600);
PAINT GREEN (2323 600);
DISPLAY INVISIBLE (2323 600);
FORCEADD TAP..1
(2325 800);
FORCEPROP 3 LASTPIN (2275 800) SIG_NAME M_A_CPU1_SA_CS_N<0>
J 0
(2285 810);
DISPLAY 0.659574 (2285 810);
PAINT MONO (2285 810);
DISPLAY INVISIBLE (2285 810);
FORCEPROP 1 LASTPIN (2275 800) BN 0
J 0
(2263 808);
DISPLAY 0.680851 (2263 808);
PAINT GREEN (2263 808);
FORCEPROP 2 LAST CDS_LIB standard
J 0
(2325 800);
DISPLAY INVISIBLE (2325 800);
FORCEPROP 1 LAST BODY_TYPE PLUMBING
J 0
(2325 850);
DISPLAY 0.872340 (2325 850);
PAINT GREEN (2325 850);
DISPLAY INVISIBLE (2325 850);
FORCEPROP 1 LAST HDL_TAP TRUE
J 0
(2650 675);
DISPLAY 0.872340 (2650 675);
DISPLAY INVISIBLE (2650 675);
FORCEPROP 1 LAST PATH I97
J 0
(2323 800);
DISPLAY 0.872340 (2323 800);
PAINT GREEN (2323 800);
DISPLAY INVISIBLE (2323 800);
FORCEADD TAP..1
(2325 850);
FORCEPROP 3 LASTPIN (2275 850) SIG_NAME M_A_CPU1_SA_CS_N<1>
J 0
(2285 860);
DISPLAY 0.659574 (2285 860);
PAINT MONO (2285 860);
DISPLAY INVISIBLE (2285 860);
FORCEPROP 1 LASTPIN (2275 850) BN 1
J 0
(2263 858);
DISPLAY 0.680851 (2263 858);
PAINT GREEN (2263 858);
FORCEPROP 2 LAST CDS_LIB standard
J 0
(2325 850);
DISPLAY INVISIBLE (2325 850);
FORCEPROP 1 LAST BODY_TYPE PLUMBING
J 0
(2325 900);
DISPLAY 0.872340 (2325 900);
PAINT GREEN (2325 900);
DISPLAY INVISIBLE (2325 900);
FORCEPROP 1 LAST HDL_TAP TRUE
J 0
(2650 725);
DISPLAY 0.872340 (2650 725);
DISPLAY INVISIBLE (2650 725);
FORCEPROP 1 LAST PATH I98
J 0
(2323 850);
DISPLAY 0.872340 (2323 850);
PAINT GREEN (2323 850);
DISPLAY INVISIBLE (2323 850);
FORCEADD TAP..1
(2325 900);
FORCEPROP 3 LASTPIN (2275 900) SIG_NAME M_A_CPU1_SA_CS_N<2>
J 0
(2285 910);
DISPLAY 0.659574 (2285 910);
PAINT MONO (2285 910);
DISPLAY INVISIBLE (2285 910);
FORCEPROP 1 LASTPIN (2275 900) BN 2
J 0
(2263 908);
DISPLAY 0.680851 (2263 908);
PAINT GREEN (2263 908);
FORCEPROP 2 LAST CDS_LIB standard
J 0
(2325 900);
DISPLAY INVISIBLE (2325 900);
FORCEPROP 1 LAST BODY_TYPE PLUMBING
J 0
(2325 950);
DISPLAY 0.872340 (2325 950);
PAINT GREEN (2325 950);
DISPLAY INVISIBLE (2325 950);
FORCEPROP 1 LAST HDL_TAP TRUE
J 0
(2650 775);
DISPLAY 0.872340 (2650 775);
DISPLAY INVISIBLE (2650 775);
FORCEPROP 1 LAST PATH I99
J 0
(2323 900);
DISPLAY 0.872340 (2323 900);
PAINT GREEN (2323 900);
DISPLAY INVISIBLE (2323 900);
FORCEADD QUANTA_TITLE_BLOCK_C..1
(5250 -1250);
FORCEPROP 0 LAST CDS_CON_LAST_MODIFIED Fri Aug 25 14:00:33 2023
J 0
(3365 -1235);
PAINT MONO (3365 -1235);
DISPLAY INVISIBLE (3365 -1235);
FORCEPROP 2 LAST CUSTOM_TXT_CDS <XR_PAGE_TITLE>
J 0
(-2640 4000);
DISPLAY 0.638298 (-2640 4000);
PAINT PINK (-2640 4000);
DISPLAY INVISIBLE (-2640 4000);
FORCEPROP 2 LAST CUSTOM_TXT_CDS <CON_LAST_MODIFIED>
J 0
(3350 -1225);
DISPLAY 0.978723 (3350 -1225);
FORCEPROP 2 LAST CUSTOM_TXT_CDS <Q_NUMBER>
J 0
(3847 -1147);
DISPLAY 1.212766 (3847 -1147);
FORCEPROP 2 LAST CUSTOM_TXT_CDS <CON_PAGE_NUM> OF <CON_TOTAL_PAGES>
J 0
(4800 -1225);
DISPLAY 0.978723 (4800 -1225);
FORCEPROP 2 LAST CUSTOM_TXT_CDS <Q_REV>
J 0
(5066 -1147);
DISPLAY 1.212766 (5066 -1147);
FORCEPROP 2 LAST CUSTOM_TXT_CDS <Q_PROJ>
J 0
(2868 -1148);
DISPLAY 1.212766 (2868 -1148);
FORCEPROP 1 LAST CUSTOM_TXT_CDS <NAME_2>
J 0
(2075 -1200);
FORCEPROP 1 LAST CUSTOM_TXT_CDS <NAME_1>
J 0
(2075 -1075);
FORCEPROP 1 LAST Q_TITLE SPR CPU1 - DDR CH A (8 OF 30)
J 0
(-4116 -1224);
DISPLAY 1.957447 (-4116 -1224);
PAINT GREEN (-4116 -1224);
FORCEPROP 1 LAST Q_DEPT 
J 1
(1487 -1201);
DISPLAY 1.957447 (1487 -1201);
PAINT GREEN (1487 -1201);
FORCEPROP 1 LAST COMMENT_BODY TRUE
J 0
(5262 -1263);
DISPLAY 0.978723 (5262 -1263);
PAINT GREEN (5262 -1263);
DISPLAY INVISIBLE (5262 -1263);
FORCEPROP 2 LAST CDS_XR_PAGE_TITLE CR-51 : @S9S_MB_2U_LIB.S9S_MB_2U(SCH_1):PAGE51
J 0
(-2640 4000);
DISPLAY 0.638298 (-2640 4000);
PAINT PINK (-2640 4000);
DISPLAY INVISIBLE (-2640 4000);
FORCEPROP 2 LAST CDS_LIB pure_quanta
J 0
(5250 -1250);
PAINT MONO (5250 -1250);
DISPLAY INVISIBLE (5250 -1250);
FORCEPROP 1 LAST CDS_LMAN_SYM_OUTLINE -9475,6775,100,-125
J 0
(5250 -1250);
DISPLAY 0.468085 (5250 -1250);
PAINT GREEN (5250 -1250);
DISPLAY INVISIBLE (5250 -1250);
FORCEPROP 2 LAST PAGE_BORDER TRUE
J 0
(-2640 4000);
DISPLAY 0.638298 (-2640 4000);
PAINT PINK (-2640 4000);
DISPLAY INVISIBLE (-2640 4000);
WIRE 17 -1 (2375 1975)(3375 1975);
FORCEPROP 2 LAST SIG_NAME M_A_CPU1_SA_CA<6:0>
J 0
(2515 1985);
DISPLAY 0.680851 (2515 1985);
PAINT WHITE (2515 1985);
WIRE 17 -1 (2375 1925)(2375 1975);
WIRE 17 -1 (2375 1875)(2375 1925);
WIRE 17 -1 (2375 1825)(2375 1875);
WIRE 17 -1 (2375 1775)(2375 1825);
WIRE 17 -1 (2375 1725)(2375 1775);
WIRE 17 -1 (2375 1675)(2375 1725);
WIRE 17 -1 (2375 975)(3375 975);
FORCEPROP 2 LAST SIG_NAME M_A_CPU1_SA_CS_N<3:0>
J 0
(2515 985);
DISPLAY 0.680851 (2515 985);
PAINT WHITE (2515 985);
WIRE 17 -1 (2375 925)(2375 975);
WIRE 17 -1 (2375 875)(2375 925);
WIRE 17 -1 (2375 825)(2375 875);
WIRE 17 -1 (2375 3725)(3375 3725);
FORCEPROP 2 LAST SIG_NAME M_A_CPU1_SA_DQS_DN<9:0>
J 0
(2515 3735);
DISPLAY 0.680851 (2515 3735);
PAINT WHITE (2515 3735);
WIRE 17 -1 (2375 3675)(2375 3725);
WIRE 17 -1 (2375 3625)(2375 3675);
WIRE 17 -1 (2375 3575)(2375 3625);
WIRE 17 -1 (2375 3525)(2375 3575);
WIRE 17 -1 (2375 3475)(2375 3525);
WIRE 17 -1 (2375 3425)(2375 3475);
WIRE 17 -1 (2375 3375)(2375 3425);
WIRE 17 -1 (2375 3325)(2375 3375);
WIRE 17 -1 (2375 3275)(2375 3325);
WIRE 17 -1 (2375 4275)(3375 4275);
FORCEPROP 2 LAST SIG_NAME M_A_CPU1_SA_DQS_DP<9:0>
J 0
(2515 4285);
DISPLAY 0.680851 (2515 4285);
PAINT WHITE (2515 4285);
WIRE 17 -1 (2375 4225)(2375 4275);
WIRE 17 -1 (2375 4175)(2375 4225);
WIRE 17 -1 (2375 4125)(2375 4175);
WIRE 17 -1 (2375 4075)(2375 4125);
WIRE 17 -1 (2375 4025)(2375 4075);
WIRE 17 -1 (2375 3975)(2375 4025);
WIRE 17 -1 (2375 3925)(2375 3975);
WIRE 17 -1 (2375 3875)(2375 3925);
WIRE 17 -1 (2375 3825)(2375 3875);
WIRE 17 -1 (2375 1475)(3375 1475);
FORCEPROP 2 LAST SIG_NAME M_A_CPU1_SB_CA<6:0>
J 0
(2515 1485);
DISPLAY 0.680851 (2515 1485);
PAINT WHITE (2515 1485);
WIRE 17 -1 (2375 1425)(2375 1475);
WIRE 17 -1 (2375 1375)(2375 1425);
WIRE 17 -1 (2375 1325)(2375 1375);
WIRE 17 -1 (2375 1275)(2375 1325);
WIRE 17 -1 (2375 1225)(2375 1275);
WIRE 17 -1 (2375 1175)(2375 1225);
WIRE 17 -1 (2375 675)(3375 675);
FORCEPROP 2 LAST SIG_NAME M_A_CPU1_SB_CS_N<3:0>
J 0
(2515 685);
DISPLAY 0.680851 (2515 685);
PAINT WHITE (2515 685);
WIRE 17 -1 (2375 625)(2375 675);
WIRE 17 -1 (2375 575)(2375 625);
WIRE 17 -1 (2375 525)(2375 575);
WIRE 17 -1 (2375 2575)(3375 2575);
FORCEPROP 2 LAST SIG_NAME M_A_CPU1_SB_DQS_DN<9:0>
J 0
(2515 2585);
DISPLAY 0.680851 (2515 2585);
PAINT WHITE (2515 2585);
WIRE 17 -1 (2375 2525)(2375 2575);
WIRE 17 -1 (2375 2475)(2375 2525);
WIRE 17 -1 (2375 2425)(2375 2475);
WIRE 17 -1 (2375 2375)(2375 2425);
WIRE 17 -1 (2375 2325)(2375 2375);
WIRE 17 -1 (2375 2275)(2375 2325);
WIRE 17 -1 (2375 2225)(2375 2275);
WIRE 17 -1 (2375 2175)(2375 2225);
WIRE 17 -1 (2375 2125)(2375 2175);
WIRE 17 -1 (2375 3125)(3375 3125);
FORCEPROP 2 LAST SIG_NAME M_A_CPU1_SB_DQS_DP<9:0>
J 0
(2515 3135);
DISPLAY 0.680851 (2515 3135);
PAINT WHITE (2515 3135);
WIRE 17 -1 (2375 3075)(2375 3125);
WIRE 17 -1 (2375 3025)(2375 3075);
WIRE 17 -1 (2375 2975)(2375 3025);
WIRE 17 -1 (2375 2925)(2375 2975);
WIRE 17 -1 (2375 2875)(2375 2925);
WIRE 17 -1 (2375 2825)(2375 2875);
WIRE 17 -1 (2375 2775)(2375 2825);
WIRE 17 -1 (2375 2725)(2375 2775);
WIRE 17 -1 (2375 2675)(2375 2725);
WIRE 17 -1 (-1150 325)(-1150 375);
WIRE 17 -1 (-1150 375)(-1150 425);
WIRE 17 -1 (-1150 425)(-1150 475);
WIRE 17 -1 (-1150 475)(-1150 525);
WIRE 17 -1 (-1150 525)(-1150 575);
WIRE 17 -1 (-1150 575)(-1150 625);
WIRE 17 -1 (-1150 625)(-1150 675);
WIRE 17 -1 (-2075 675)(-1150 675);
FORCEPROP 2 LAST SIG_NAME M_A_CPU1_SB_CB<7:0>
J 0
(-1935 685);
DISPLAY 0.680851 (-1935 685);
PAINT WHITE (-1935 685);
WIRE 17 -1 (-1150 725)(-1150 775);
WIRE 17 -1 (-1150 775)(-1150 825);
WIRE 17 -1 (-1150 825)(-1150 875);
WIRE 17 -1 (-1150 875)(-1150 925);
WIRE 17 -1 (-1150 925)(-1150 975);
WIRE 17 -1 (-1150 975)(-1150 1025);
WIRE 17 -1 (-1150 1025)(-1150 1075);
WIRE 17 -1 (-1150 1075)(-1150 1125);
WIRE 17 -1 (-1150 1125)(-1150 1175);
WIRE 17 -1 (-1150 1175)(-1150 1225);
WIRE 17 -1 (-1150 1225)(-1150 1275);
WIRE 17 -1 (-1150 1275)(-1150 1325);
WIRE 17 -1 (-1150 1325)(-1150 1375);
WIRE 17 -1 (-1150 1375)(-1150 1425);
WIRE 17 -1 (-1150 1425)(-1150 1475);
WIRE 17 -1 (-1150 1475)(-1150 1525);
WIRE 17 -1 (-1150 1525)(-1150 1575);
WIRE 17 -1 (-1150 1575)(-1150 1625);
WIRE 17 -1 (-1150 1625)(-1150 1675);
WIRE 17 -1 (-1150 1675)(-1150 1725);
WIRE 17 -1 (-1150 1725)(-1150 1775);
WIRE 17 -1 (-1150 1775)(-1150 1825);
WIRE 17 -1 (-1150 1825)(-1150 1875);
WIRE 17 -1 (-1150 1875)(-1150 1925);
WIRE 17 -1 (-1150 1925)(-1150 1975);
WIRE 17 -1 (-1150 1975)(-1150 2025);
WIRE 17 -1 (-1150 2025)(-1150 2075);
WIRE 17 -1 (-1150 2075)(-1150 2125);
WIRE 17 -1 (-1150 2125)(-1150 2175);
WIRE 17 -1 (-1150 2175)(-1150 2225);
WIRE 17 -1 (-1150 2225)(-1150 2275);
WIRE 17 -1 (-2075 2275)(-1150 2275);
FORCEPROP 2 LAST SIG_NAME M_A_CPU1_SB_DQ<31:0>
J 0
(-1935 2285);
DISPLAY 0.680851 (-1935 2285);
PAINT WHITE (-1935 2285);
WIRE 17 -1 (-1150 2325)(-1150 2375);
WIRE 17 -1 (-1150 2375)(-1150 2425);
WIRE 17 -1 (-1150 2425)(-1150 2475);
WIRE 17 -1 (-1150 2475)(-1150 2525);
WIRE 17 -1 (-1150 2525)(-1150 2575);
WIRE 17 -1 (-1150 2575)(-1150 2625);
WIRE 17 -1 (-1150 2625)(-1150 2675);
WIRE 17 -1 (-2075 2675)(-1150 2675);
FORCEPROP 2 LAST SIG_NAME M_A_CPU1_SA_CB<7:0>
J 0
(-1935 2685);
DISPLAY 0.680851 (-1935 2685);
PAINT WHITE (-1935 2685);
WIRE 17 -1 (-1150 2725)(-1150 2775);
WIRE 17 -1 (-1150 2775)(-1150 2825);
WIRE 17 -1 (-1150 2825)(-1150 2875);
WIRE 17 -1 (-1150 2875)(-1150 2925);
WIRE 17 -1 (-1150 2925)(-1150 2975);
WIRE 17 -1 (-1150 2975)(-1150 3025);
WIRE 17 -1 (-1150 3025)(-1150 3075);
WIRE 17 -1 (-1150 3075)(-1150 3125);
WIRE 17 -1 (-1150 3125)(-1150 3175);
WIRE 17 -1 (-1150 3175)(-1150 3225);
WIRE 17 -1 (-1150 3225)(-1150 3275);
WIRE 17 -1 (-1150 3275)(-1150 3325);
WIRE 17 -1 (-1150 3325)(-1150 3375);
WIRE 17 -1 (-1150 3375)(-1150 3425);
WIRE 17 -1 (-1150 3425)(-1150 3475);
WIRE 17 -1 (-1150 3475)(-1150 3525);
WIRE 17 -1 (-1150 3525)(-1150 3575);
WIRE 17 -1 (-1150 3575)(-1150 3625);
WIRE 17 -1 (-1150 3625)(-1150 3675);
WIRE 17 -1 (-1150 3675)(-1150 3725);
WIRE 17 -1 (-1150 3725)(-1150 3775);
WIRE 17 -1 (-1150 3775)(-1150 3825);
WIRE 17 -1 (-1150 3825)(-1150 3875);
WIRE 17 -1 (-1150 3875)(-1150 3925);
WIRE 17 -1 (-1150 3925)(-1150 3975);
WIRE 17 -1 (-1150 3975)(-1150 4025);
WIRE 17 -1 (-1150 4025)(-1150 4075);
WIRE 17 -1 (-1150 4075)(-1150 4125);
WIRE 17 -1 (-1150 4125)(-1150 4175);
WIRE 17 -1 (-1150 4175)(-1150 4225);
WIRE 17 -1 (-1150 4225)(-1150 4275);
WIRE 17 -1 (-2075 4275)(-1150 4275);
FORCEPROP 2 LAST SIG_NAME M_A_CPU1_SA_DQ<31:0>
J 0
(-1935 4285);
DISPLAY 0.680851 (-1935 4285);
PAINT WHITE (-1935 4285);
WIRE 17 -1 (-1150 175)(-1150 225);
WIRE 17 -1 (-2075 225)(-1150 225);
FORCEPROP 2 LAST SIG_NAME M_A_CPU1_CLK_DP<1:0>
J 0
(-1935 235);
DISPLAY 0.680851 (-1935 235);
PAINT WHITE (-1935 235);
WIRE 17 -1 (-1150 75)(-1150 125);
WIRE 17 -1 (-2075 125)(-1150 125);
FORCEPROP 2 LAST SIG_NAME M_A_CPU1_CLK_DN<1:0>
J 0
(-1935 135);
DISPLAY 0.680851 (-1935 135);
PAINT WHITE (-1935 135);
WIRE 16 -1 (-1050 4050)(-600 4050);
WIRE 16 -1 (-1050 4000)(-600 4000);
WIRE 16 -1 (-1050 3950)(-600 3950);
WIRE 16 -1 (-1050 3900)(-600 3900);
WIRE 16 -1 (-1050 3850)(-600 3850);
WIRE 16 -1 (-1050 3800)(-600 3800);
WIRE 16 -1 (-1050 100)(-600 100);
WIRE 16 -1 (-1050 50)(-600 50);
WIRE 16 -1 (-1050 200)(-600 200);
WIRE 16 -1 (-1050 150)(-600 150);
WIRE 16 -1 (-1050 4250)(-600 4250);
WIRE 16 -1 (-1050 4200)(-600 4200);
WIRE 16 -1 (-1050 4150)(-600 4150);
WIRE 16 -1 (-1050 4100)(-600 4100);
WIRE 16 -1 (-1050 3750)(-600 3750);
WIRE 16 -1 (-1050 3700)(-600 3700);
WIRE 16 -1 (-1050 3650)(-600 3650);
WIRE 16 -1 (-1050 3600)(-600 3600);
WIRE 16 -1 (-1050 3550)(-600 3550);
WIRE 16 -1 (-1050 3500)(-600 3500);
WIRE 16 -1 (-1050 3450)(-600 3450);
WIRE 16 -1 (-1050 3400)(-600 3400);
WIRE 16 -1 (-1050 3350)(-600 3350);
WIRE 16 -1 (-1050 3300)(-600 3300);
WIRE 16 -1 (-1050 3250)(-600 3250);
WIRE 16 -1 (-1050 3200)(-600 3200);
WIRE 16 -1 (-1050 3150)(-600 3150);
WIRE 16 -1 (-1050 3100)(-600 3100);
WIRE 16 -1 (-1050 3050)(-600 3050);
WIRE 16 -1 (-1050 3000)(-600 3000);
WIRE 16 -1 (-1050 2950)(-600 2950);
WIRE 16 -1 (-1050 2900)(-600 2900);
WIRE 16 -1 (-1050 2850)(-600 2850);
WIRE 16 -1 (-1050 2800)(-600 2800);
WIRE 16 -1 (-1050 2750)(-600 2750);
WIRE 16 -1 (-1050 2700)(-600 2700);
WIRE 16 -1 (-1050 2650)(-600 2650);
WIRE 16 -1 (-1050 2600)(-600 2600);
WIRE 16 -1 (-1050 2550)(-600 2550);
WIRE 16 -1 (-1050 2500)(-600 2500);
WIRE 16 -1 (-1050 2450)(-600 2450);
WIRE 16 -1 (-1050 2400)(-600 2400);
WIRE 16 -1 (-1050 2350)(-600 2350);
WIRE 16 -1 (-1050 2300)(-600 2300);
WIRE 16 -1 (-1050 2250)(-600 2250);
WIRE 16 -1 (-1050 2200)(-600 2200);
WIRE 16 -1 (-1050 2150)(-600 2150);
WIRE 16 -1 (-1050 2100)(-600 2100);
WIRE 16 -1 (-1050 2050)(-600 2050);
WIRE 16 -1 (-1050 2000)(-600 2000);
WIRE 16 -1 (-1050 1950)(-600 1950);
WIRE 16 -1 (-1050 1900)(-600 1900);
WIRE 16 -1 (-1050 1850)(-600 1850);
WIRE 16 -1 (-1050 1800)(-600 1800);
WIRE 16 -1 (-1050 1750)(-600 1750);
WIRE 16 -1 (-1050 1700)(-600 1700);
WIRE 16 -1 (-1050 1650)(-600 1650);
WIRE 16 -1 (-1050 1600)(-600 1600);
WIRE 16 -1 (-1050 1550)(-600 1550);
WIRE 16 -1 (-1050 1500)(-600 1500);
WIRE 16 -1 (-1050 1450)(-600 1450);
WIRE 16 -1 (-1050 1400)(-600 1400);
WIRE 16 -1 (-1050 1350)(-600 1350);
WIRE 16 -1 (-1050 1300)(-600 1300);
WIRE 16 -1 (-1050 1250)(-600 1250);
WIRE 16 -1 (-1050 1200)(-600 1200);
WIRE 16 -1 (-1050 1150)(-600 1150);
WIRE 16 -1 (-1050 1100)(-600 1100);
WIRE 16 -1 (-1050 1050)(-600 1050);
WIRE 16 -1 (-1050 1000)(-600 1000);
WIRE 16 -1 (-1050 950)(-600 950);
WIRE 16 -1 (-1050 900)(-600 900);
WIRE 16 -1 (-1050 850)(-600 850);
WIRE 16 -1 (-1050 800)(-600 800);
WIRE 16 -1 (-1050 750)(-600 750);
WIRE 16 -1 (-1050 700)(-600 700);
WIRE 16 -1 (-1050 650)(-600 650);
WIRE 16 -1 (-1050 600)(-600 600);
WIRE 16 -1 (-1050 550)(-600 550);
WIRE 16 -1 (-1050 500)(-600 500);
WIRE 16 -1 (-1050 450)(-600 450);
WIRE 16 -1 (-1050 400)(-600 400);
WIRE 16 -1 (-1050 350)(-600 350);
WIRE 16 -1 (-1050 300)(-600 300);
WIRE 16 -1 (3375 1100)(1850 1100);
FORCEPROP 2 LAST SIG_NAME M_A_CPU1_SB_PAR
J 0
(2484 1109);
DISPLAY 0.680851 (2484 1109);
PAINT WHITE (2484 1109);
WIRE 16 -1 (1850 2650)(2275 2650);
WIRE 16 -1 (1850 2700)(2275 2700);
WIRE 16 -1 (1850 2750)(2275 2750);
WIRE 16 -1 (1850 2800)(2275 2800);
WIRE 16 -1 (1850 2850)(2275 2850);
WIRE 16 -1 (1850 2900)(2275 2900);
WIRE 16 -1 (1850 2950)(2275 2950);
WIRE 16 -1 (1850 3000)(2275 3000);
WIRE 16 -1 (1850 3050)(2275 3050);
WIRE 16 -1 (1850 3100)(2275 3100);
WIRE 16 -1 (1850 2100)(2275 2100);
WIRE 16 -1 (1850 2150)(2275 2150);
WIRE 16 -1 (1850 2200)(2275 2200);
WIRE 16 -1 (1850 2250)(2275 2250);
WIRE 16 -1 (1850 2300)(2275 2300);
WIRE 16 -1 (1850 2350)(2275 2350);
WIRE 16 -1 (1850 2400)(2275 2400);
WIRE 16 -1 (1850 2450)(2275 2450);
WIRE 16 -1 (1850 2500)(2275 2500);
WIRE 16 -1 (1850 2550)(2275 2550);
WIRE 16 -1 (1850 500)(2275 500);
WIRE 16 -1 (1850 550)(2275 550);
WIRE 16 -1 (1850 600)(2275 600);
WIRE 16 -1 (1850 650)(2275 650);
WIRE 16 -1 (1850 1150)(2275 1150);
WIRE 16 -1 (1850 1200)(2275 1200);
WIRE 16 -1 (1850 1250)(2275 1250);
WIRE 16 -1 (1850 1300)(2275 1300);
WIRE 16 -1 (1850 1350)(2275 1350);
WIRE 16 -1 (1850 1400)(2275 1400);
WIRE 16 -1 (1850 1450)(2275 1450);
WIRE 16 -1 (3375 1600)(1850 1600);
FORCEPROP 2 LAST SIG_NAME M_A_CPU1_SA_PAR
J 0
(2484 1609);
DISPLAY 0.680851 (2484 1609);
PAINT WHITE (2484 1609);
WIRE 16 -1 (1850 3800)(2275 3800);
WIRE 16 -1 (1850 3850)(2275 3850);
WIRE 16 -1 (1850 3900)(2275 3900);
WIRE 16 -1 (1850 3950)(2275 3950);
WIRE 16 -1 (1850 4000)(2275 4000);
WIRE 16 -1 (1850 4050)(2275 4050);
WIRE 16 -1 (1850 4100)(2275 4100);
WIRE 16 -1 (1850 4150)(2275 4150);
WIRE 16 -1 (1850 4200)(2275 4200);
WIRE 16 -1 (1850 4250)(2275 4250);
WIRE 16 -1 (1850 3250)(2275 3250);
WIRE 16 -1 (1850 3300)(2275 3300);
WIRE 16 -1 (1850 3350)(2275 3350);
WIRE 16 -1 (1850 3400)(2275 3400);
WIRE 16 -1 (1850 3450)(2275 3450);
WIRE 16 -1 (1850 3500)(2275 3500);
WIRE 16 -1 (1850 3550)(2275 3550);
WIRE 16 -1 (1850 3600)(2275 3600);
WIRE 16 -1 (1850 3650)(2275 3650);
WIRE 16 -1 (1850 3700)(2275 3700);
WIRE 16 -1 (1850 800)(2275 800);
WIRE 16 -1 (1850 850)(2275 850);
WIRE 16 -1 (1850 900)(2275 900);
WIRE 16 -1 (1850 950)(2275 950);
WIRE 16 -1 (1850 1650)(2275 1650);
WIRE 16 -1 (1850 1700)(2275 1700);
WIRE 16 -1 (1850 1750)(2275 1750);
WIRE 16 -1 (1850 1800)(2275 1800);
WIRE 16 -1 (1850 1850)(2275 1850);
WIRE 16 -1 (1850 1900)(2275 1900);
WIRE 16 -1 (1850 1950)(2275 1950);
WIRE 16 -1 (3375 150)(1850 150);
FORCEPROP 2 LAST SIG_NAME M_A_CPU1_SB_RSP<0>
J 0
(2484 159);
DISPLAY 0.680851 (2484 159);
PAINT WHITE (2484 159);
WIRE 16 -1 (3375 200)(1850 200);
FORCEPROP 2 LAST SIG_NAME M_A_CPU1_SB_RSP<1>
J 0
(2484 209);
DISPLAY 0.680851 (2484 209);
PAINT WHITE (2484 209);
WIRE 16 -1 (3375 300)(1850 300);
FORCEPROP 2 LAST SIG_NAME M_A_CPU1_SA_RSP<0>
J 0
(2484 309);
DISPLAY 0.680851 (2484 309);
PAINT WHITE (2484 309);
WIRE 16 -1 (3375 350)(1850 350);
FORCEPROP 2 LAST SIG_NAME M_A_CPU1_SA_RSP<1>
J 0
(2484 359);
DISPLAY 0.680851 (2484 359);
PAINT WHITE (2484 359);
WIRE 16 -1 (3375 50)(1850 50);
FORCEPROP 2 LAST SIG_NAME M_A_CPU1_ALERT_N
J 0
(2484 59);
DISPLAY 0.680851 (2484 59);
PAINT WHITE (2484 59);
QUIT
